(kicad_sch
	(version 20250114)
	(generator "eeschema")
	(generator_version "9.0")
	(paper "A3")
	(title_block
		(title "Kintex 410T devboard")
		(date "2024-04-03")
		(rev "1.1.2")
	)
	(text "FMC HPC"
		(exclude_from_sim no)
		(at 17.78 20.32 0)
		(effects
			(font
				(size 1.27 1.27)
				(thickness 0.4978)
				(bold yes)
			)
			(justify left bottom)
		)
	)
	(text "Place close to connector"
		(exclude_from_sim no)
		(at 325.628 142.24 0)
		(effects
			(font
				(size 1.27 1.27)
			)
			(justify left bottom)
		)
	)
	(text "Resistors needed to comply with standard HCSL PCIe clock.\nRoute REFCLK as 50 Ohm SE (or 100 Ohm diff)"
		(exclude_from_sim no)
		(at 321.31 24.765 0)
		(effects
			(font
				(size 1.27 1.27)
			)
			(justify left bottom)
		)
	)
	(junction
		(at 29.21 44.45)
		(diameter 0)
		(color 0 0 0 0)
	)
	(junction
		(at 130.81 39.37)
		(diameter 0)
		(color 0 0 0 0)
	)
	(junction
		(at 111.76 189.23)
		(diameter 0)
		(color 0 0 0 0)
	)
	(junction
		(at 203.2 57.15)
		(diameter 0)
		(color 0 0 0 0)
	)
	(junction
		(at 213.36 59.69)
		(diameter 0)
		(color 0 0 0 0)
	)
	(junction
		(at 38.1 44.45)
		(diameter 0)
		(color 0 0 0 0)
	)
	(no_connect
		(at 284.48 217.17)
	)
	(no_connect
		(at 284.48 257.81)
	)
	(no_connect
		(at 93.98 151.13)
	)
	(no_connect
		(at 130.81 227.33)
	)
	(no_connect
		(at 248.92 199.39)
	)
	(no_connect
		(at 151.13 59.69)
	)
	(no_connect
		(at 93.98 113.03)
	)
	(no_connect
		(at 93.98 115.57)
	)
	(no_connect
		(at 184.15 127)
	)
	(no_connect
		(at 280.67 68.58)
	)
	(no_connect
		(at 151.13 114.3)
	)
	(no_connect
		(at 248.92 196.85)
	)
	(no_connect
		(at 248.92 229.87)
	)
	(no_connect
		(at 60.96 113.03)
	)
	(no_connect
		(at 130.81 257.81)
	)
	(no_connect
		(at 93.98 123.19)
	)
	(no_connect
		(at 184.15 106.68)
	)
	(no_connect
		(at 163.83 252.73)
	)
	(no_connect
		(at 248.92 265.43)
	)
	(no_connect
		(at 151.13 132.08)
	)
	(no_connect
		(at 163.83 262.89)
	)
	(no_connect
		(at 248.92 252.73)
	)
	(no_connect
		(at 184.15 129.54)
	)
	(no_connect
		(at 280.67 83.82)
	)
	(no_connect
		(at 130.81 201.93)
	)
	(no_connect
		(at 93.98 143.51)
	)
	(no_connect
		(at 248.92 194.31)
	)
	(no_connect
		(at 93.98 148.59)
	)
	(no_connect
		(at 248.92 242.57)
	)
	(no_connect
		(at 163.83 217.17)
	)
	(no_connect
		(at 248.92 212.09)
	)
	(no_connect
		(at 279.4 115.57)
	)
	(no_connect
		(at 248.92 270.51)
	)
	(no_connect
		(at 248.92 214.63)
	)
	(no_connect
		(at 184.15 114.3)
	)
	(no_connect
		(at 248.92 232.41)
	)
	(no_connect
		(at 184.15 132.08)
	)
	(no_connect
		(at 60.96 115.57)
	)
	(no_connect
		(at 93.98 120.65)
	)
	(no_connect
		(at 60.96 107.95)
	)
	(no_connect
		(at 130.81 234.95)
	)
	(no_connect
		(at 130.81 250.19)
	)
	(no_connect
		(at 163.83 237.49)
	)
	(no_connect
		(at 97.79 43.18)
	)
	(no_connect
		(at 284.48 204.47)
	)
	(no_connect
		(at 248.92 262.89)
	)
	(no_connect
		(at 248.92 217.17)
	)
	(no_connect
		(at 163.83 214.63)
	)
	(no_connect
		(at 280.67 53.34)
	)
	(no_connect
		(at 130.81 209.55)
	)
	(no_connect
		(at 284.48 214.63)
	)
	(no_connect
		(at 163.83 229.87)
	)
	(no_connect
		(at 93.98 110.49)
	)
	(no_connect
		(at 130.81 212.09)
	)
	(no_connect
		(at 151.13 99.06)
	)
	(no_connect
		(at 163.83 260.35)
	)
	(no_connect
		(at 130.81 214.63)
	)
	(no_connect
		(at 151.13 96.52)
	)
	(no_connect
		(at 60.96 140.97)
	)
	(no_connect
		(at 279.4 110.49)
	)
	(no_connect
		(at 151.13 137.16)
	)
	(no_connect
		(at 93.98 133.35)
	)
	(no_connect
		(at 248.92 222.25)
	)
	(no_connect
		(at 163.83 250.19)
	)
	(no_connect
		(at 163.83 257.81)
	)
	(no_connect
		(at 284.48 262.89)
	)
	(no_connect
		(at 280.67 48.26)
	)
	(no_connect
		(at 280.67 60.96)
	)
	(no_connect
		(at 248.92 227.33)
	)
	(no_connect
		(at 248.92 237.49)
	)
	(no_connect
		(at 130.81 237.49)
	)
	(no_connect
		(at 248.92 255.27)
	)
	(no_connect
		(at 284.48 265.43)
	)
	(no_connect
		(at 130.81 247.65)
	)
	(no_connect
		(at 130.81 245.11)
	)
	(no_connect
		(at 130.81 219.71)
	)
	(no_connect
		(at 130.81 222.25)
	)
	(no_connect
		(at 151.13 57.15)
	)
	(no_connect
		(at 280.67 55.88)
	)
	(no_connect
		(at 284.48 270.51)
	)
	(no_connect
		(at 130.81 217.17)
	)
	(no_connect
		(at 93.98 130.81)
	)
	(no_connect
		(at 248.92 224.79)
	)
	(no_connect
		(at 284.48 194.31)
	)
	(no_connect
		(at 184.15 91.44)
	)
	(no_connect
		(at 151.13 134.62)
	)
	(no_connect
		(at 163.83 267.97)
	)
	(no_connect
		(at 284.48 267.97)
	)
	(no_connect
		(at 248.92 240.03)
	)
	(no_connect
		(at 184.15 109.22)
	)
	(no_connect
		(at 284.48 222.25)
	)
	(no_connect
		(at 280.67 58.42)
	)
	(no_connect
		(at 248.92 245.11)
	)
	(no_connect
		(at 60.96 123.19)
	)
	(no_connect
		(at 284.48 199.39)
	)
	(no_connect
		(at 60.96 143.51)
	)
	(no_connect
		(at 280.67 50.8)
	)
	(no_connect
		(at 60.96 110.49)
	)
	(no_connect
		(at 248.92 247.65)
	)
	(no_connect
		(at 93.98 118.11)
	)
	(no_connect
		(at 284.48 250.19)
	)
	(no_connect
		(at 248.92 260.35)
	)
	(no_connect
		(at 248.92 273.05)
	)
	(no_connect
		(at 93.98 105.41)
	)
	(no_connect
		(at 284.48 240.03)
	)
	(no_connect
		(at 284.48 219.71)
	)
	(no_connect
		(at 130.81 232.41)
	)
	(no_connect
		(at 163.83 191.77)
	)
	(no_connect
		(at 163.83 234.95)
	)
	(no_connect
		(at 284.48 252.73)
	)
	(no_connect
		(at 97.79 45.72)
	)
	(no_connect
		(at 163.83 186.69)
	)
	(no_connect
		(at 280.67 73.66)
	)
	(no_connect
		(at 184.15 111.76)
	)
	(no_connect
		(at 93.98 100.33)
	)
	(no_connect
		(at 60.96 130.81)
	)
	(no_connect
		(at 284.48 209.55)
	)
	(no_connect
		(at 93.98 125.73)
	)
	(no_connect
		(at 248.92 257.81)
	)
	(no_connect
		(at 284.48 232.41)
	)
	(no_connect
		(at 284.48 212.09)
	)
	(no_connect
		(at 163.83 265.43)
	)
	(no_connect
		(at 93.98 138.43)
	)
	(no_connect
		(at 93.98 97.79)
	)
	(no_connect
		(at 93.98 146.05)
	)
	(no_connect
		(at 151.13 142.24)
	)
	(no_connect
		(at 151.13 144.78)
	)
	(no_connect
		(at 60.96 151.13)
	)
	(no_connect
		(at 284.48 196.85)
	)
	(no_connect
		(at 279.4 107.95)
	)
	(no_connect
		(at 93.98 107.95)
	)
	(no_connect
		(at 184.15 96.52)
	)
	(no_connect
		(at 130.81 191.77)
	)
	(no_connect
		(at 130.81 229.87)
	)
	(no_connect
		(at 163.83 184.15)
	)
	(no_connect
		(at 284.48 227.33)
	)
	(no_connect
		(at 151.13 91.44)
	)
	(no_connect
		(at 151.13 93.98)
	)
	(no_connect
		(at 184.15 101.6)
	)
	(no_connect
		(at 130.81 199.39)
	)
	(no_connect
		(at 284.48 237.49)
	)
	(no_connect
		(at 248.92 207.01)
	)
	(no_connect
		(at 130.81 252.73)
	)
	(no_connect
		(at 184.15 93.98)
	)
	(no_connect
		(at 163.83 232.41)
	)
	(no_connect
		(at 184.15 99.06)
	)
	(no_connect
		(at 60.96 118.11)
	)
	(no_connect
		(at 280.67 86.36)
	)
	(no_connect
		(at 151.13 111.76)
	)
	(no_connect
		(at 279.4 113.03)
	)
	(no_connect
		(at 151.13 139.7)
	)
	(no_connect
		(at 284.48 201.93)
	)
	(no_connect
		(at 130.81 194.31)
	)
	(no_connect
		(at 93.98 102.87)
	)
	(no_connect
		(at 280.67 66.04)
	)
	(no_connect
		(at 248.92 250.19)
	)
	(no_connect
		(at 163.83 189.23)
	)
	(no_connect
		(at 280.67 71.12)
	)
	(no_connect
		(at 60.96 120.65)
	)
	(no_connect
		(at 280.67 78.74)
	)
	(no_connect
		(at 280.67 43.18)
	)
	(no_connect
		(at 284.48 245.11)
	)
	(no_connect
		(at 280.67 81.28)
	)
	(no_connect
		(at 280.67 45.72)
	)
	(no_connect
		(at 284.48 234.95)
	)
	(no_connect
		(at 151.13 36.83)
	)
	(no_connect
		(at 93.98 140.97)
	)
	(no_connect
		(at 130.81 207.01)
	)
	(no_connect
		(at 284.48 242.57)
	)
	(no_connect
		(at 184.15 134.62)
	)
	(no_connect
		(at 93.98 128.27)
	)
	(no_connect
		(at 130.81 204.47)
	)
	(no_connect
		(at 60.96 138.43)
	)
	(no_connect
		(at 130.81 196.85)
	)
	(no_connect
		(at 130.81 186.69)
	)
	(no_connect
		(at 130.81 224.79)
	)
	(no_connect
		(at 284.48 229.87)
	)
	(no_connect
		(at 60.96 125.73)
	)
	(no_connect
		(at 60.96 148.59)
	)
	(no_connect
		(at 248.92 201.93)
	)
	(no_connect
		(at 284.48 260.35)
	)
	(no_connect
		(at 151.13 119.38)
	)
	(no_connect
		(at 248.92 204.47)
	)
	(no_connect
		(at 151.13 116.84)
	)
	(no_connect
		(at 184.15 104.14)
	)
	(no_connect
		(at 67.31 43.18)
	)
	(no_connect
		(at 60.96 146.05)
	)
	(no_connect
		(at 93.98 135.89)
	)
	(no_connect
		(at 284.48 273.05)
	)
	(no_connect
		(at 248.92 219.71)
	)
	(no_connect
		(at 284.48 255.27)
	)
	(no_connect
		(at 284.48 207.01)
	)
	(no_connect
		(at 248.92 209.55)
	)
	(no_connect
		(at 130.81 184.15)
	)
	(no_connect
		(at 284.48 224.79)
	)
	(no_connect
		(at 130.81 255.27)
	)
	(no_connect
		(at 248.92 267.97)
	)
	(no_connect
		(at 284.48 247.65)
	)
	(no_connect
		(at 248.92 234.95)
	)
	(bus_entry
		(at 134.62 147.32)
		(size -1.27 -1.27)
		(stroke
			(width 0)
			(type default)
		)
	)
	(bus_entry
		(at 180.34 201.93)
		(size 1.27 -1.27)
		(stroke
			(width 0)
			(type default)
		)
	)
	(bus_entry
		(at 381 220.98)
		(size 1.27 1.27)
		(stroke
			(width 0)
			(type default)
		)
	)
	(bus_entry
		(at 381 182.88)
		(size 1.27 -1.27)
		(stroke
			(width 0)
			(type default)
		)
	)
	(bus_entry
		(at 369.57 124.46)
		(size 1.27 -1.27)
		(stroke
			(width 0)
			(type default)
		)
	)
	(bus_entry
		(at 134.62 106.68)
		(size -1.27 -1.27)
		(stroke
			(width 0)
			(type default)
		)
	)
	(bus_entry
		(at 134.62 124.46)
		(size -1.27 -1.27)
		(stroke
			(width 0)
			(type default)
		)
	)
	(bus_entry
		(at 381 180.34)
		(size 1.27 -1.27)
		(stroke
			(width 0)
			(type default)
		)
	)
	(bus_entry
		(at 200.66 144.78)
		(size 1.27 -1.27)
		(stroke
			(width 0)
			(type default)
		)
	)
	(bus_entry
		(at 114.3 260.35)
		(size -1.27 -1.27)
		(stroke
			(width 0)
			(type default)
		)
	)
	(bus_entry
		(at 200.66 121.92)
		(size 1.27 -1.27)
		(stroke
			(width 0)
			(type default)
		)
	)
	(bus_entry
		(at 180.34 242.57)
		(size 1.27 -1.27)
		(stroke
			(width 0)
			(type default)
		)
	)
	(bus_entry
		(at 180.34 212.09)
		(size 1.27 -1.27)
		(stroke
			(width 0)
			(type default)
		)
	)
	(bus_entry
		(at 180.34 194.31)
		(size 1.27 -1.27)
		(stroke
			(width 0)
			(type default)
		)
	)
	(bus_entry
		(at 381 162.56)
		(size 1.27 -1.27)
		(stroke
			(width 0)
			(type default)
		)
	)
	(bus_entry
		(at 381 160.02)
		(size 1.27 -1.27)
		(stroke
			(width 0)
			(type default)
		)
	)
	(bus_entry
		(at 44.45 133.35)
		(size -1.27 -1.27)
		(stroke
			(width 0)
			(type default)
		)
	)
	(bus_entry
		(at 114.3 262.89)
		(size -1.27 -1.27)
		(stroke
			(width 0)
			(type default)
		)
	)
	(bus_entry
		(at 134.62 129.54)
		(size -1.27 -1.27)
		(stroke
			(width 0)
			(type default)
		)
	)
	(bus_entry
		(at 386.08 66.04)
		(size 1.27 1.27)
		(stroke
			(width 0)
			(type default)
		)
	)
	(bus_entry
		(at 134.62 121.92)
		(size -1.27 -1.27)
		(stroke
			(width 0)
			(type default)
		)
	)
	(bus_entry
		(at 109.22 189.23)
		(size -1.27 0)
		(stroke
			(width 0)
			(type default)
		)
	)
	(bus_entry
		(at 114.3 242.57)
		(size -1.27 -1.27)
		(stroke
			(width 0)
			(type default)
		)
	)
	(bus_entry
		(at 200.66 142.24)
		(size 1.27 -1.27)
		(stroke
			(width 0)
			(type default)
		)
	)
	(bus_entry
		(at 386.08 45.72)
		(size 1.27 -1.27)
		(stroke
			(width 0)
			(type default)
		)
	)
	(bus_entry
		(at 180.34 199.39)
		(size 1.27 -1.27)
		(stroke
			(width 0)
			(type default)
		)
	)
	(bus_entry
		(at 369.57 102.87)
		(size 1.27 -1.27)
		(stroke
			(width 0)
			(type default)
		)
	)
	(bus_entry
		(at 381 172.72)
		(size 1.27 -1.27)
		(stroke
			(width 0)
			(type default)
		)
	)
	(bus_entry
		(at 369.57 92.71)
		(size 1.27 -1.27)
		(stroke
			(width 0)
			(type default)
		)
	)
	(bus_entry
		(at 381 151.13)
		(size 1.27 -1.27)
		(stroke
			(width 0)
			(type default)
		)
	)
	(bus_entry
		(at 369.57 116.84)
		(size 1.27 -1.27)
		(stroke
			(width 0)
			(type default)
		)
	)
	(bus_entry
		(at 198.12 48.26)
		(size -1.27 1.27)
		(stroke
			(width 0)
			(type default)
		)
	)
	(bus_entry
		(at 198.12 43.18)
		(size -1.27 1.27)
		(stroke
			(width 0)
			(type default)
		)
	)
	(bus_entry
		(at 198.12 45.72)
		(size -1.27 1.27)
		(stroke
			(width 0)
			(type default)
		)
	)
	(bus_entry
		(at 134.62 104.14)
		(size -1.27 -1.27)
		(stroke
			(width 0)
			(type default)
		)
	)
	(bus_entry
		(at 381 200.66)
		(size 1.27 1.27)
		(stroke
			(width 0)
			(type default)
		)
	)
	(bus_entry
		(at 381 190.5)
		(size 1.27 1.27)
		(stroke
			(width 0)
			(type default)
		)
	)
	(bus_entry
		(at 200.66 137.16)
		(size 1.27 -1.27)
		(stroke
			(width 0)
			(type default)
		)
	)
	(bus_entry
		(at 200.66 119.38)
		(size 1.27 -1.27)
		(stroke
			(width 0)
			(type default)
		)
	)
	(bus_entry
		(at 369.57 90.17)
		(size 1.27 -1.27)
		(stroke
			(width 0)
			(type default)
		)
	)
	(bus_entry
		(at 369.57 100.33)
		(size 1.27 -1.27)
		(stroke
			(width 0)
			(type default)
		)
	)
	(bus_entry
		(at 386.08 36.83)
		(size 1.27 -1.27)
		(stroke
			(width 0)
			(type default)
		)
	)
	(bus_entry
		(at 180.34 207.01)
		(size 1.27 -1.27)
		(stroke
			(width 0)
			(type default)
		)
	)
	(bus_entry
		(at 132.08 66.04)
		(size -1.27 -1.27)
		(stroke
			(width 0)
			(type default)
		)
	)
	(bus_entry
		(at 180.34 227.33)
		(size 1.27 -1.27)
		(stroke
			(width 0)
			(type default)
		)
	)
	(bus_entry
		(at 298.45 130.81)
		(size 1.27 0)
		(stroke
			(width 0)
			(type default)
		)
	)
	(bus_entry
		(at 381 213.36)
		(size 1.27 1.27)
		(stroke
			(width 0)
			(type default)
		)
	)
	(bus_entry
		(at 134.62 109.22)
		(size -1.27 -1.27)
		(stroke
			(width 0)
			(type default)
		)
	)
	(bus_entry
		(at 200.66 116.84)
		(size 1.27 -1.27)
		(stroke
			(width 0)
			(type default)
		)
	)
	(bus_entry
		(at 180.34 255.27)
		(size 1.27 -1.27)
		(stroke
			(width 0)
			(type default)
		)
	)
	(bus_entry
		(at 381 223.52)
		(size 1.27 1.27)
		(stroke
			(width 0)
			(type default)
		)
	)
	(bus_entry
		(at 114.3 265.43)
		(size -1.27 -1.27)
		(stroke
			(width 0)
			(type default)
		)
	)
	(bus_entry
		(at 44.45 135.89)
		(size -1.27 -1.27)
		(stroke
			(width 0)
			(type default)
		)
	)
	(bus_entry
		(at 198.12 50.8)
		(size -1.27 1.27)
		(stroke
			(width 0)
			(type default)
		)
	)
	(bus_entry
		(at 134.62 149.86)
		(size -1.27 -1.27)
		(stroke
			(width 0)
			(type default)
		)
	)
	(bus_entry
		(at 44.45 102.87)
		(size -1.27 -1.27)
		(stroke
			(width 0)
			(type default)
		)
	)
	(bus_entry
		(at 369.57 97.79)
		(size 1.27 -1.27)
		(stroke
			(width 0)
			(type default)
		)
	)
	(bus_entry
		(at 369.57 109.22)
		(size 1.27 -1.27)
		(stroke
			(width 0)
			(type default)
		)
	)
	(bus_entry
		(at 44.45 128.27)
		(size -1.27 -1.27)
		(stroke
			(width 0)
			(type default)
		)
	)
	(bus_entry
		(at 134.62 101.6)
		(size -1.27 -1.27)
		(stroke
			(width 0)
			(type default)
		)
	)
	(bus_entry
		(at 114.3 240.03)
		(size -1.27 -1.27)
		(stroke
			(width 0)
			(type default)
		)
	)
	(bus_entry
		(at 369.57 95.25)
		(size 1.27 -1.27)
		(stroke
			(width 0)
			(type default)
		)
	)
	(bus_entry
		(at 386.08 55.88)
		(size 1.27 1.27)
		(stroke
			(width 0)
			(type default)
		)
	)
	(bus_entry
		(at 180.34 247.65)
		(size 1.27 -1.27)
		(stroke
			(width 0)
			(type default)
		)
	)
	(bus_entry
		(at 200.66 147.32)
		(size 1.27 -1.27)
		(stroke
			(width 0)
			(type default)
		)
	)
	(bus_entry
		(at 381 148.59)
		(size 1.27 -1.27)
		(stroke
			(width 0)
			(type default)
		)
	)
	(bus_entry
		(at 369.57 127)
		(size 1.27 -1.27)
		(stroke
			(width 0)
			(type default)
		)
	)
	(bus_entry
		(at 386.08 53.34)
		(size 1.27 1.27)
		(stroke
			(width 0)
			(type default)
		)
	)
	(bus_entry
		(at 180.34 224.79)
		(size 1.27 -1.27)
		(stroke
			(width 0)
			(type default)
		)
	)
	(bus_entry
		(at 369.57 111.76)
		(size 1.27 -1.27)
		(stroke
			(width 0)
			(type default)
		)
	)
	(bus_entry
		(at 180.34 245.11)
		(size 1.27 -1.27)
		(stroke
			(width 0)
			(type default)
		)
	)
	(bus_entry
		(at 381 210.82)
		(size 1.27 1.27)
		(stroke
			(width 0)
			(type default)
		)
	)
	(bus_entry
		(at 44.45 105.41)
		(size -1.27 -1.27)
		(stroke
			(width 0)
			(type default)
		)
	)
	(bus_entry
		(at 180.34 204.47)
		(size 1.27 -1.27)
		(stroke
			(width 0)
			(type default)
		)
	)
	(bus_entry
		(at 369.57 114.3)
		(size 1.27 -1.27)
		(stroke
			(width 0)
			(type default)
		)
	)
	(bus_entry
		(at 114.3 267.97)
		(size -1.27 -1.27)
		(stroke
			(width 0)
			(type default)
		)
	)
	(bus_entry
		(at 369.57 87.63)
		(size 1.27 -1.27)
		(stroke
			(width 0)
			(type default)
		)
	)
	(bus_entry
		(at 180.34 196.85)
		(size 1.27 -1.27)
		(stroke
			(width 0)
			(type default)
		)
	)
	(bus_entry
		(at 381 193.04)
		(size 1.27 1.27)
		(stroke
			(width 0)
			(type default)
		)
	)
	(bus_entry
		(at 180.34 222.25)
		(size 1.27 -1.27)
		(stroke
			(width 0)
			(type default)
		)
	)
	(bus_entry
		(at 44.45 97.79)
		(size -1.27 -1.27)
		(stroke
			(width 0)
			(type default)
		)
	)
	(bus_entry
		(at 198.12 40.64)
		(size -1.27 1.27)
		(stroke
			(width 0)
			(type default)
		)
	)
	(bus_entry
		(at 386.08 63.5)
		(size 1.27 1.27)
		(stroke
			(width 0)
			(type default)
		)
	)
	(bus_entry
		(at 369.57 119.38)
		(size 1.27 -1.27)
		(stroke
			(width 0)
			(type default)
		)
	)
	(bus_entry
		(at 44.45 100.33)
		(size -1.27 -1.27)
		(stroke
			(width 0)
			(type default)
		)
	)
	(bus_entry
		(at 180.34 219.71)
		(size 1.27 -1.27)
		(stroke
			(width 0)
			(type default)
		)
	)
	(bus_entry
		(at 381 203.2)
		(size 1.27 1.27)
		(stroke
			(width 0)
			(type default)
		)
	)
	(bus_entry
		(at 200.66 149.86)
		(size 1.27 -1.27)
		(stroke
			(width 0)
			(type default)
		)
	)
	(bus_entry
		(at 200.66 139.7)
		(size 1.27 -1.27)
		(stroke
			(width 0)
			(type default)
		)
	)
	(bus_entry
		(at 180.34 240.03)
		(size 1.27 -1.27)
		(stroke
			(width 0)
			(type default)
		)
	)
	(bus_entry
		(at 200.66 124.46)
		(size 1.27 -1.27)
		(stroke
			(width 0)
			(type default)
		)
	)
	(bus_entry
		(at 369.57 121.92)
		(size 1.27 -1.27)
		(stroke
			(width 0)
			(type default)
		)
	)
	(bus_entry
		(at 381 170.18)
		(size 1.27 -1.27)
		(stroke
			(width 0)
			(type default)
		)
	)
	(bus_entry
		(at 134.62 127)
		(size -1.27 -1.27)
		(stroke
			(width 0)
			(type default)
		)
	)
	(bus_entry
		(at 386.08 43.18)
		(size 1.27 -1.27)
		(stroke
			(width 0)
			(type default)
		)
	)
	(bus_entry
		(at 369.57 105.41)
		(size 1.27 -1.27)
		(stroke
			(width 0)
			(type default)
		)
	)
	(bus_entry
		(at 180.34 209.55)
		(size 1.27 -1.27)
		(stroke
			(width 0)
			(type default)
		)
	)
	(bus_entry
		(at 386.08 34.29)
		(size 1.27 -1.27)
		(stroke
			(width 0)
			(type default)
		)
	)
	(wire
		(pts
			(xy 360.68 147.32) (xy 353.06 147.32)
		)
		(stroke
			(width 0)
			(type default)
		)
	)
	(bus
		(pts
			(xy 370.84 96.52) (xy 370.84 99.06)
		)
		(stroke
			(width 0)
			(type default)
		)
	)
	(wire
		(pts
			(xy 44.45 105.41) (xy 60.96 105.41)
		)
		(stroke
			(width 0)
			(type default)
		)
	)
	(bus
		(pts
			(xy 111.76 236.22) (xy 110.49 236.22)
		)
		(stroke
			(width 0)
			(type default)
		)
	)
	(wire
		(pts
			(xy 233.68 163.83) (xy 248.92 163.83)
		)
		(stroke
			(width 0)
			(type default)
		)
	)
	(wire
		(pts
			(xy 180.34 199.39) (xy 163.83 199.39)
		)
		(stroke
			(width 0)
			(type default)
		)
	)
	(wire
		(pts
			(xy 341.63 184.15) (xy 347.98 184.15)
		)
		(stroke
			(width 0)
			(type default)
		)
	)
	(bus
		(pts
			(xy 370.84 120.65) (xy 370.84 123.19)
		)
		(stroke
			(width 0)
			(type default)
		)
	)
	(wire
		(pts
			(xy 341.63 199.39) (xy 347.98 199.39)
		)
		(stroke
			(width 0)
			(type default)
		)
	)
	(bus
		(pts
			(xy 381 143.51) (xy 382.27 144.78)
		)
		(stroke
			(width 0)
			(type default)
		)
	)
	(bus
		(pts
			(xy 203.2 113.03) (xy 201.93 114.3)
		)
		(stroke
			(width 0)
			(type default)
		)
	)
	(bus
		(pts
			(xy 382.27 227.33) (xy 382.27 224.79)
		)
		(stroke
			(width 0)
			(type default)
		)
	)
	(wire
		(pts
			(xy 341.63 152.4) (xy 347.98 152.4)
		)
		(stroke
			(width 0)
			(type default)
		)
	)
	(wire
		(pts
			(xy 354.33 52.07) (xy 361.95 52.07)
		)
		(stroke
			(width 0)
			(type default)
		)
	)
	(bus
		(pts
			(xy 384.81 27.94) (xy 387.35 29.21)
		)
		(stroke
			(width 0)
			(type default)
		)
	)
	(bus
		(pts
			(xy 43.18 101.6) (xy 43.18 104.14)
		)
		(stroke
			(width 0)
			(type default)
		)
	)
	(wire
		(pts
			(xy 233.68 173.99) (xy 248.92 173.99)
		)
		(stroke
			(width 0)
			(type default)
		)
	)
	(wire
		(pts
			(xy 139.7 26.67) (xy 139.7 30.48)
		)
		(stroke
			(width 0)
			(type default)
		)
	)
	(wire
		(pts
			(xy 342.9 52.07) (xy 349.25 52.07)
		)
		(stroke
			(width 0)
			(type default)
		)
	)
	(wire
		(pts
			(xy 114.3 242.57) (xy 130.81 242.57)
		)
		(stroke
			(width 0)
			(type default)
		)
	)
	(wire
		(pts
			(xy 360.68 220.98) (xy 360.68 219.71)
		)
		(stroke
			(width 0)
			(type default)
		)
	)
	(bus
		(pts
			(xy 300.99 130.81) (xy 299.72 130.81)
		)
		(stroke
			(width 0)
			(type default)
		)
	)
	(bus
		(pts
			(xy 182.88 190.5) (xy 181.61 191.77)
		)
		(stroke
			(width 0)
			(type default)
		)
	)
	(wire
		(pts
			(xy 354.33 38.1) (xy 361.95 38.1)
		)
		(stroke
			(width 0)
			(type default)
		)
	)
	(wire
		(pts
			(xy 111.76 185.42) (xy 111.76 189.23)
		)
		(stroke
			(width 0)
			(type default)
		)
	)
	(wire
		(pts
			(xy 38.1 53.34) (xy 38.1 57.15)
		)
		(stroke
			(width 0)
			(type default)
		)
	)
	(wire
		(pts
			(xy 284.48 181.61) (xy 299.72 181.61)
		)
		(stroke
			(width 0)
			(type default)
		)
	)
	(bus
		(pts
			(xy 181.61 198.12) (xy 181.61 200.66)
		)
		(stroke
			(width 0)
			(type default)
		)
	)
	(wire
		(pts
			(xy 233.68 189.23) (xy 248.92 189.23)
		)
		(stroke
			(width 0)
			(type default)
		)
	)
	(wire
		(pts
			(xy 233.68 158.75) (xy 248.92 158.75)
		)
		(stroke
			(width 0)
			(type default)
		)
	)
	(wire
		(pts
			(xy 38.1 44.45) (xy 38.1 48.26)
		)
		(stroke
			(width 0)
			(type default)
		)
	)
	(wire
		(pts
			(xy 284.48 173.99) (xy 299.72 173.99)
		)
		(stroke
			(width 0)
			(type default)
		)
	)
	(wire
		(pts
			(xy 97.79 38.1) (xy 105.41 38.1)
		)
		(stroke
			(width 0)
			(type default)
		)
	)
	(wire
		(pts
			(xy 322.58 66.04) (xy 342.9 66.04)
		)
		(stroke
			(width 0)
			(type default)
		)
	)
	(wire
		(pts
			(xy 342.9 46.99) (xy 349.25 46.99)
		)
		(stroke
			(width 0)
			(type default)
		)
	)
	(bus
		(pts
			(xy 370.84 99.06) (xy 370.84 101.6)
		)
		(stroke
			(width 0)
			(type default)
		)
	)
	(wire
		(pts
			(xy 341.63 172.72) (xy 341.63 173.99)
		)
		(stroke
			(width 0)
			(type default)
		)
	)
	(wire
		(pts
			(xy 360.68 193.04) (xy 360.68 194.31)
		)
		(stroke
			(width 0)
			(type default)
		)
	)
	(wire
		(pts
			(xy 180.34 242.57) (xy 163.83 242.57)
		)
		(stroke
			(width 0)
			(type default)
		)
	)
	(wire
		(pts
			(xy 342.9 52.07) (xy 342.9 53.34)
		)
		(stroke
			(width 0)
			(type default)
		)
	)
	(bus
		(pts
			(xy 382.27 149.86) (xy 382.27 158.75)
		)
		(stroke
			(width 0)
			(type default)
		)
	)
	(wire
		(pts
			(xy 325.12 220.98) (xy 341.63 220.98)
		)
		(stroke
			(width 0)
			(type default)
		)
	)
	(wire
		(pts
			(xy 44.45 133.35) (xy 60.96 133.35)
		)
		(stroke
			(width 0)
			(type default)
		)
	)
	(bus
		(pts
			(xy 372.11 85.09) (xy 370.84 86.36)
		)
		(stroke
			(width 0)
			(type default)
		)
	)
	(wire
		(pts
			(xy 180.34 240.03) (xy 163.83 240.03)
		)
		(stroke
			(width 0)
			(type default)
		)
	)
	(wire
		(pts
			(xy 341.63 148.59) (xy 341.63 147.32)
		)
		(stroke
			(width 0)
			(type default)
		)
	)
	(bus
		(pts
			(xy 387.35 67.31) (xy 387.35 71.12)
		)
		(stroke
			(width 0)
			(type default)
		)
	)
	(wire
		(pts
			(xy 180.34 245.11) (xy 163.83 245.11)
		)
		(stroke
			(width 0)
			(type default)
		)
	)
	(wire
		(pts
			(xy 342.9 33.02) (xy 342.9 34.29)
		)
		(stroke
			(width 0)
			(type default)
		)
	)
	(wire
		(pts
			(xy 134.62 147.32) (xy 151.13 147.32)
		)
		(stroke
			(width 0)
			(type default)
		)
	)
	(wire
		(pts
			(xy 360.68 213.36) (xy 360.68 214.63)
		)
		(stroke
			(width 0)
			(type default)
		)
	)
	(wire
		(pts
			(xy 280.67 35.56) (xy 302.26 35.56)
		)
		(stroke
			(width 0)
			(type default)
		)
	)
	(wire
		(pts
			(xy 360.68 158.75) (xy 353.06 158.75)
		)
		(stroke
			(width 0)
			(type default)
		)
	)
	(wire
		(pts
			(xy 354.33 46.99) (xy 361.95 46.99)
		)
		(stroke
			(width 0)
			(type default)
		)
	)
	(wire
		(pts
			(xy 361.95 36.83) (xy 386.08 36.83)
		)
		(stroke
			(width 0)
			(type default)
		)
	)
	(wire
		(pts
			(xy 341.63 200.66) (xy 341.63 199.39)
		)
		(stroke
			(width 0)
			(type default)
		)
	)
	(bus
		(pts
			(xy 370.84 123.19) (xy 370.84 125.73)
		)
		(stroke
			(width 0)
			(type default)
		)
	)
	(wire
		(pts
			(xy 62.23 38.1) (xy 67.31 38.1)
		)
		(stroke
			(width 0)
			(type default)
		)
	)
	(wire
		(pts
			(xy 284.48 161.29) (xy 299.72 161.29)
		)
		(stroke
			(width 0)
			(type default)
		)
	)
	(wire
		(pts
			(xy 196.85 46.99) (xy 181.61 46.99)
		)
		(stroke
			(width 0)
			(type default)
		)
	)
	(wire
		(pts
			(xy 284.48 158.75) (xy 299.72 158.75)
		)
		(stroke
			(width 0)
			(type default)
		)
	)
	(wire
		(pts
			(xy 203.2 52.07) (xy 203.2 57.15)
		)
		(stroke
			(width 0)
			(type default)
		)
	)
	(bus
		(pts
			(xy 382.27 214.63) (xy 382.27 222.25)
		)
		(stroke
			(width 0)
			(type default)
		)
	)
	(wire
		(pts
			(xy 233.68 171.45) (xy 248.92 171.45)
		)
		(stroke
			(width 0)
			(type default)
		)
	)
	(bus
		(pts
			(xy 198.12 40.64) (xy 198.12 31.75)
		)
		(stroke
			(width 0)
			(type default)
		)
	)
	(wire
		(pts
			(xy 360.68 210.82) (xy 381 210.82)
		)
		(stroke
			(width 0)
			(type default)
		)
	)
	(bus
		(pts
			(xy 370.84 91.44) (xy 370.84 93.98)
		)
		(stroke
			(width 0)
			(type default)
		)
	)
	(bus
		(pts
			(xy 382.27 204.47) (xy 382.27 212.09)
		)
		(stroke
			(width 0)
			(type default)
		)
	)
	(wire
		(pts
			(xy 360.68 189.23) (xy 353.06 189.23)
		)
		(stroke
			(width 0)
			(type default)
		)
	)
	(bus
		(pts
			(xy 182.88 190.5) (xy 184.15 190.5)
		)
		(stroke
			(width 0)
			(type default)
		)
	)
	(wire
		(pts
			(xy 181.61 57.15) (xy 203.2 57.15)
		)
		(stroke
			(width 0)
			(type default)
		)
	)
	(bus
		(pts
			(xy 181.61 210.82) (xy 181.61 218.44)
		)
		(stroke
			(width 0)
			(type default)
		)
	)
	(wire
		(pts
			(xy 280.67 38.1) (xy 302.26 38.1)
		)
		(stroke
			(width 0)
			(type default)
		)
	)
	(wire
		(pts
			(xy 134.62 127) (xy 151.13 127)
		)
		(stroke
			(width 0)
			(type default)
		)
	)
	(wire
		(pts
			(xy 341.63 179.07) (xy 347.98 179.07)
		)
		(stroke
			(width 0)
			(type default)
		)
	)
	(wire
		(pts
			(xy 44.45 97.79) (xy 60.96 97.79)
		)
		(stroke
			(width 0)
			(type default)
		)
	)
	(wire
		(pts
			(xy 341.63 220.98) (xy 341.63 219.71)
		)
		(stroke
			(width 0)
			(type default)
		)
	)
	(wire
		(pts
			(xy 325.12 160.02) (xy 341.63 160.02)
		)
		(stroke
			(width 0)
			(type default)
		)
	)
	(wire
		(pts
			(xy 325.12 180.34) (xy 341.63 180.34)
		)
		(stroke
			(width 0)
			(type default)
		)
	)
	(wire
		(pts
			(xy 342.9 66.04) (xy 342.9 67.31)
		)
		(stroke
			(width 0)
			(type default)
		)
	)
	(wire
		(pts
			(xy 325.12 210.82) (xy 341.63 210.82)
		)
		(stroke
			(width 0)
			(type default)
		)
	)
	(wire
		(pts
			(xy 44.45 102.87) (xy 60.96 102.87)
		)
		(stroke
			(width 0)
			(type default)
		)
	)
	(wire
		(pts
			(xy 130.81 35.56) (xy 130.81 39.37)
		)
		(stroke
			(width 0)
			(type default)
		)
	)
	(wire
		(pts
			(xy 354.33 62.23) (xy 361.95 62.23)
		)
		(stroke
			(width 0)
			(type default)
		)
	)
	(wire
		(pts
			(xy 284.48 191.77) (xy 299.72 191.77)
		)
		(stroke
			(width 0)
			(type default)
		)
	)
	(wire
		(pts
			(xy 134.62 124.46) (xy 151.13 124.46)
		)
		(stroke
			(width 0)
			(type default)
		)
	)
	(bus
		(pts
			(xy 384.81 72.39) (xy 369.57 72.39)
		)
		(stroke
			(width 0)
			(type default)
		)
	)
	(wire
		(pts
			(xy 233.68 191.77) (xy 248.92 191.77)
		)
		(stroke
			(width 0)
			(type default)
		)
	)
	(bus
		(pts
			(xy 382.27 191.77) (xy 382.27 194.31)
		)
		(stroke
			(width 0)
			(type default)
		)
	)
	(wire
		(pts
			(xy 105.41 35.56) (xy 105.41 38.1)
		)
		(stroke
			(width 0)
			(type default)
		)
	)
	(wire
		(pts
			(xy 341.63 168.91) (xy 347.98 168.91)
		)
		(stroke
			(width 0)
			(type default)
		)
	)
	(wire
		(pts
			(xy 369.57 109.22) (xy 336.55 109.22)
		)
		(stroke
			(width 0)
			(type default)
		)
	)
	(wire
		(pts
			(xy 107.95 40.64) (xy 107.95 35.56)
		)
		(stroke
			(width 0)
			(type default)
		)
	)
	(bus
		(pts
			(xy 370.84 88.9) (xy 370.84 91.44)
		)
		(stroke
			(width 0)
			(type default)
		)
	)
	(wire
		(pts
			(xy 342.9 38.1) (xy 349.25 38.1)
		)
		(stroke
			(width 0)
			(type default)
		)
	)
	(bus
		(pts
			(xy 379.73 229.87) (xy 382.27 227.33)
		)
		(stroke
			(width 0)
			(type default)
		)
	)
	(bus
		(pts
			(xy 133.35 105.41) (xy 133.35 107.95)
		)
		(stroke
			(width 0)
			(type default)
		)
	)
	(wire
		(pts
			(xy 369.57 90.17) (xy 336.55 90.17)
		)
		(stroke
			(width 0)
			(type default)
		)
	)
	(wire
		(pts
			(xy 180.34 255.27) (xy 163.83 255.27)
		)
		(stroke
			(width 0)
			(type default)
		)
	)
	(wire
		(pts
			(xy 341.63 224.79) (xy 347.98 224.79)
		)
		(stroke
			(width 0)
			(type default)
		)
	)
	(bus
		(pts
			(xy 43.18 96.52) (xy 43.18 99.06)
		)
		(stroke
			(width 0)
			(type default)
		)
	)
	(wire
		(pts
			(xy 360.68 151.13) (xy 360.68 152.4)
		)
		(stroke
			(width 0)
			(type default)
		)
	)
	(wire
		(pts
			(xy 325.12 151.13) (xy 341.63 151.13)
		)
		(stroke
			(width 0)
			(type default)
		)
	)
	(wire
		(pts
			(xy 360.68 204.47) (xy 353.06 204.47)
		)
		(stroke
			(width 0)
			(type default)
		)
	)
	(wire
		(pts
			(xy 322.58 53.34) (xy 342.9 53.34)
		)
		(stroke
			(width 0)
			(type default)
		)
	)
	(bus
		(pts
			(xy 387.35 64.77) (xy 387.35 67.31)
		)
		(stroke
			(width 0)
			(type default)
		)
	)
	(bus
		(pts
			(xy 181.61 205.74) (xy 181.61 208.28)
		)
		(stroke
			(width 0)
			(type default)
		)
	)
	(wire
		(pts
			(xy 360.68 219.71) (xy 353.06 219.71)
		)
		(stroke
			(width 0)
			(type default)
		)
	)
	(bus
		(pts
			(xy 133.35 125.73) (xy 133.35 128.27)
		)
		(stroke
			(width 0)
			(type default)
		)
	)
	(wire
		(pts
			(xy 360.68 193.04) (xy 381 193.04)
		)
		(stroke
			(width 0)
			(type default)
		)
	)
	(wire
		(pts
			(xy 360.68 224.79) (xy 353.06 224.79)
		)
		(stroke
			(width 0)
			(type default)
		)
	)
	(wire
		(pts
			(xy 361.95 55.88) (xy 361.95 57.15)
		)
		(stroke
			(width 0)
			(type default)
		)
	)
	(wire
		(pts
			(xy 29.21 39.37) (xy 29.21 44.45)
		)
		(stroke
			(width 0)
			(type default)
		)
	)
	(wire
		(pts
			(xy 360.68 190.5) (xy 381 190.5)
		)
		(stroke
			(width 0)
			(type default)
		)
	)
	(wire
		(pts
			(xy 325.12 223.52) (xy 341.63 223.52)
		)
		(stroke
			(width 0)
			(type default)
		)
	)
	(wire
		(pts
			(xy 341.63 209.55) (xy 347.98 209.55)
		)
		(stroke
			(width 0)
			(type default)
		)
	)
	(wire
		(pts
			(xy 233.68 179.07) (xy 248.92 179.07)
		)
		(stroke
			(width 0)
			(type default)
		)
	)
	(wire
		(pts
			(xy 29.21 44.45) (xy 38.1 44.45)
		)
		(stroke
			(width 0)
			(type default)
		)
	)
	(bus
		(pts
			(xy 41.91 93.98) (xy 43.18 95.25)
		)
		(stroke
			(width 0)
			(type default)
		)
	)
	(bus
		(pts
			(xy 201.93 143.51) (xy 201.93 146.05)
		)
		(stroke
			(width 0)
			(type default)
		)
	)
	(bus
		(pts
			(xy 379.73 143.51) (xy 381 143.51)
		)
		(stroke
			(width 0)
			(type default)
		)
	)
	(wire
		(pts
			(xy 360.68 180.34) (xy 360.68 179.07)
		)
		(stroke
			(width 0)
			(type default)
		)
	)
	(wire
		(pts
			(xy 369.57 102.87) (xy 336.55 102.87)
		)
		(stroke
			(width 0)
			(type default)
		)
	)
	(wire
		(pts
			(xy 284.48 184.15) (xy 299.72 184.15)
		)
		(stroke
			(width 0)
			(type default)
		)
	)
	(bus
		(pts
			(xy 201.93 123.19) (xy 201.93 135.89)
		)
		(stroke
			(width 0)
			(type default)
		)
	)
	(wire
		(pts
			(xy 134.62 106.68) (xy 151.13 106.68)
		)
		(stroke
			(width 0)
			(type default)
		)
	)
	(wire
		(pts
			(xy 181.61 52.07) (xy 196.85 52.07)
		)
		(stroke
			(width 0)
			(type default)
		)
	)
	(wire
		(pts
			(xy 341.63 203.2) (xy 341.63 204.47)
		)
		(stroke
			(width 0)
			(type default)
		)
	)
	(wire
		(pts
			(xy 361.95 52.07) (xy 361.95 53.34)
		)
		(stroke
			(width 0)
			(type default)
		)
	)
	(wire
		(pts
			(xy 325.12 190.5) (xy 341.63 190.5)
		)
		(stroke
			(width 0)
			(type default)
		)
	)
	(wire
		(pts
			(xy 134.62 149.86) (xy 151.13 149.86)
		)
		(stroke
			(width 0)
			(type default)
		)
	)
	(bus
		(pts
			(xy 387.35 54.61) (xy 387.35 57.15)
		)
		(stroke
			(width 0)
			(type default)
		)
	)
	(wire
		(pts
			(xy 360.68 200.66) (xy 381 200.66)
		)
		(stroke
			(width 0)
			(type default)
		)
	)
	(wire
		(pts
			(xy 114.3 260.35) (xy 130.81 260.35)
		)
		(stroke
			(width 0)
			(type default)
		)
	)
	(bus
		(pts
			(xy 387.35 35.56) (xy 387.35 41.91)
		)
		(stroke
			(width 0)
			(type default)
		)
	)
	(bus
		(pts
			(xy 199.39 30.48) (xy 198.12 31.75)
		)
		(stroke
			(width 0)
			(type default)
		)
	)
	(wire
		(pts
			(xy 284.48 153.67) (xy 299.72 153.67)
		)
		(stroke
			(width 0)
			(type default)
		)
	)
	(bus
		(pts
			(xy 181.61 246.38) (xy 181.61 254)
		)
		(stroke
			(width 0)
			(type default)
		)
	)
	(bus
		(pts
			(xy 370.84 107.95) (xy 370.84 110.49)
		)
		(stroke
			(width 0)
			(type default)
		)
	)
	(bus
		(pts
			(xy 43.18 127) (xy 43.18 132.08)
		)
		(stroke
			(width 0)
			(type default)
		)
	)
	(wire
		(pts
			(xy 180.34 247.65) (xy 163.83 247.65)
		)
		(stroke
			(width 0)
			(type default)
		)
	)
	(wire
		(pts
			(xy 280.67 40.64) (xy 302.26 40.64)
		)
		(stroke
			(width 0)
			(type default)
		)
	)
	(wire
		(pts
			(xy 369.57 97.79) (xy 336.55 97.79)
		)
		(stroke
			(width 0)
			(type default)
		)
	)
	(wire
		(pts
			(xy 109.22 189.23) (xy 111.76 189.23)
		)
		(stroke
			(width 0)
			(type default)
		)
	)
	(wire
		(pts
			(xy 134.62 101.6) (xy 151.13 101.6)
		)
		(stroke
			(width 0)
			(type default)
		)
	)
	(bus
		(pts
			(xy 201.93 146.05) (xy 201.93 148.59)
		)
		(stroke
			(width 0)
			(type default)
		)
	)
	(wire
		(pts
			(xy 341.63 151.13) (xy 341.63 152.4)
		)
		(stroke
			(width 0)
			(type default)
		)
	)
	(wire
		(pts
			(xy 360.68 199.39) (xy 353.06 199.39)
		)
		(stroke
			(width 0)
			(type default)
		)
	)
	(wire
		(pts
			(xy 29.21 29.21) (xy 29.21 34.29)
		)
		(stroke
			(width 0)
			(type default)
		)
	)
	(bus
		(pts
			(xy 181.61 191.77) (xy 181.61 193.04)
		)
		(stroke
			(width 0)
			(type default)
		)
	)
	(wire
		(pts
			(xy 67.31 53.34) (xy 64.77 53.34)
		)
		(stroke
			(width 0)
			(type default)
		)
	)
	(wire
		(pts
			(xy 341.63 189.23) (xy 347.98 189.23)
		)
		(stroke
			(width 0)
			(type default)
		)
	)
	(wire
		(pts
			(xy 233.68 161.29) (xy 248.92 161.29)
		)
		(stroke
			(width 0)
			(type default)
		)
	)
	(wire
		(pts
			(xy 151.13 41.91) (xy 148.59 41.91)
		)
		(stroke
			(width 0)
			(type default)
		)
	)
	(wire
		(pts
			(xy 325.12 182.88) (xy 341.63 182.88)
		)
		(stroke
			(width 0)
			(type default)
		)
	)
	(wire
		(pts
			(xy 341.63 193.04) (xy 341.63 194.31)
		)
		(stroke
			(width 0)
			(type default)
		)
	)
	(wire
		(pts
			(xy 360.68 180.34) (xy 381 180.34)
		)
		(stroke
			(width 0)
			(type default)
		)
	)
	(wire
		(pts
			(xy 180.34 204.47) (xy 163.83 204.47)
		)
		(stroke
			(width 0)
			(type default)
		)
	)
	(wire
		(pts
			(xy 341.63 158.75) (xy 347.98 158.75)
		)
		(stroke
			(width 0)
			(type default)
		)
	)
	(wire
		(pts
			(xy 114.3 265.43) (xy 130.81 265.43)
		)
		(stroke
			(width 0)
			(type default)
		)
	)
	(wire
		(pts
			(xy 361.95 66.04) (xy 386.08 66.04)
		)
		(stroke
			(width 0)
			(type default)
		)
	)
	(wire
		(pts
			(xy 360.68 210.82) (xy 360.68 209.55)
		)
		(stroke
			(width 0)
			(type default)
		)
	)
	(wire
		(pts
			(xy 184.15 147.32) (xy 200.66 147.32)
		)
		(stroke
			(width 0)
			(type default)
		)
	)
	(bus
		(pts
			(xy 132.08 97.79) (xy 130.81 97.79)
		)
		(stroke
			(width 0)
			(type default)
		)
	)
	(wire
		(pts
			(xy 325.12 200.66) (xy 341.63 200.66)
		)
		(stroke
			(width 0)
			(type default)
		)
	)
	(wire
		(pts
			(xy 284.48 156.21) (xy 299.72 156.21)
		)
		(stroke
			(width 0)
			(type default)
		)
	)
	(bus
		(pts
			(xy 370.84 93.98) (xy 370.84 96.52)
		)
		(stroke
			(width 0)
			(type default)
		)
	)
	(wire
		(pts
			(xy 213.36 43.18) (xy 213.36 46.99)
		)
		(stroke
			(width 0)
			(type default)
		)
	)
	(bus
		(pts
			(xy 377.19 229.87) (xy 379.73 229.87)
		)
		(stroke
			(width 0)
			(type default)
		)
	)
	(wire
		(pts
			(xy 57.15 40.64) (xy 67.31 40.64)
		)
		(stroke
			(width 0)
			(type default)
		)
	)
	(wire
		(pts
			(xy 180.34 196.85) (xy 163.83 196.85)
		)
		(stroke
			(width 0)
			(type default)
		)
	)
	(wire
		(pts
			(xy 360.68 173.99) (xy 353.06 173.99)
		)
		(stroke
			(width 0)
			(type default)
		)
	)
	(bus
		(pts
			(xy 133.35 120.65) (xy 133.35 123.19)
		)
		(stroke
			(width 0)
			(type default)
		)
	)
	(bus
		(pts
			(xy 387.35 71.12) (xy 384.81 72.39)
		)
		(stroke
			(width 0)
			(type default)
		)
	)
	(wire
		(pts
			(xy 184.15 139.7) (xy 200.66 139.7)
		)
		(stroke
			(width 0)
			(type default)
		)
	)
	(wire
		(pts
			(xy 325.12 148.59) (xy 341.63 148.59)
		)
		(stroke
			(width 0)
			(type default)
		)
	)
	(wire
		(pts
			(xy 284.48 163.83) (xy 299.72 163.83)
		)
		(stroke
			(width 0)
			(type default)
		)
	)
	(bus
		(pts
			(xy 181.61 241.3) (xy 181.61 243.84)
		)
		(stroke
			(width 0)
			(type default)
		)
	)
	(wire
		(pts
			(xy 233.68 156.21) (xy 248.92 156.21)
		)
		(stroke
			(width 0)
			(type default)
		)
	)
	(wire
		(pts
			(xy 341.63 210.82) (xy 341.63 209.55)
		)
		(stroke
			(width 0)
			(type default)
		)
	)
	(wire
		(pts
			(xy 233.68 153.67) (xy 248.92 153.67)
		)
		(stroke
			(width 0)
			(type default)
		)
	)
	(wire
		(pts
			(xy 360.68 223.52) (xy 360.68 224.79)
		)
		(stroke
			(width 0)
			(type default)
		)
	)
	(wire
		(pts
			(xy 44.45 100.33) (xy 60.96 100.33)
		)
		(stroke
			(width 0)
			(type default)
		)
	)
	(wire
		(pts
			(xy 325.12 203.2) (xy 341.63 203.2)
		)
		(stroke
			(width 0)
			(type default)
		)
	)
	(wire
		(pts
			(xy 134.62 109.22) (xy 151.13 109.22)
		)
		(stroke
			(width 0)
			(type default)
		)
	)
	(wire
		(pts
			(xy 360.68 203.2) (xy 381 203.2)
		)
		(stroke
			(width 0)
			(type default)
		)
	)
	(wire
		(pts
			(xy 184.15 142.24) (xy 200.66 142.24)
		)
		(stroke
			(width 0)
			(type default)
		)
	)
	(bus
		(pts
			(xy 113.03 261.62) (xy 113.03 264.16)
		)
		(stroke
			(width 0)
			(type default)
		)
	)
	(wire
		(pts
			(xy 280.67 33.02) (xy 302.26 33.02)
		)
		(stroke
			(width 0)
			(type default)
		)
	)
	(wire
		(pts
			(xy 354.33 33.02) (xy 361.95 33.02)
		)
		(stroke
			(width 0)
			(type default)
		)
	)
	(bus
		(pts
			(xy 133.35 99.06) (xy 133.35 100.33)
		)
		(stroke
			(width 0)
			(type default)
		)
	)
	(bus
		(pts
			(xy 198.12 50.8) (xy 198.12 48.26)
		)
		(stroke
			(width 0)
			(type default)
		)
	)
	(wire
		(pts
			(xy 341.63 214.63) (xy 347.98 214.63)
		)
		(stroke
			(width 0)
			(type default)
		)
	)
	(wire
		(pts
			(xy 342.9 36.83) (xy 342.9 38.1)
		)
		(stroke
			(width 0)
			(type default)
		)
	)
	(wire
		(pts
			(xy 361.95 62.23) (xy 361.95 63.5)
		)
		(stroke
			(width 0)
			(type default)
		)
	)
	(wire
		(pts
			(xy 369.57 92.71) (xy 336.55 92.71)
		)
		(stroke
			(width 0)
			(type default)
		)
	)
	(wire
		(pts
			(xy 196.85 41.91) (xy 181.61 41.91)
		)
		(stroke
			(width 0)
			(type default)
		)
	)
	(wire
		(pts
			(xy 342.9 55.88) (xy 342.9 57.15)
		)
		(stroke
			(width 0)
			(type default)
		)
	)
	(bus
		(pts
			(xy 370.84 115.57) (xy 370.84 118.11)
		)
		(stroke
			(width 0)
			(type default)
		)
	)
	(wire
		(pts
			(xy 134.62 121.92) (xy 151.13 121.92)
		)
		(stroke
			(width 0)
			(type default)
		)
	)
	(bus
		(pts
			(xy 387.35 33.02) (xy 387.35 35.56)
		)
		(stroke
			(width 0)
			(type default)
		)
	)
	(wire
		(pts
			(xy 203.2 57.15) (xy 220.98 57.15)
		)
		(stroke
			(width 0)
			(type default)
		)
	)
	(wire
		(pts
			(xy 360.68 182.88) (xy 360.68 184.15)
		)
		(stroke
			(width 0)
			(type default)
		)
	)
	(wire
		(pts
			(xy 360.68 220.98) (xy 381 220.98)
		)
		(stroke
			(width 0)
			(type default)
		)
	)
	(wire
		(pts
			(xy 64.77 53.34) (xy 64.77 55.88)
		)
		(stroke
			(width 0)
			(type default)
		)
	)
	(bus
		(pts
			(xy 181.61 195.58) (xy 181.61 198.12)
		)
		(stroke
			(width 0)
			(type default)
		)
	)
	(bus
		(pts
			(xy 370.84 113.03) (xy 370.84 115.57)
		)
		(stroke
			(width 0)
			(type default)
		)
	)
	(wire
		(pts
			(xy 342.9 41.91) (xy 342.9 43.18)
		)
		(stroke
			(width 0)
			(type default)
		)
	)
	(wire
		(pts
			(xy 369.57 111.76) (xy 336.55 111.76)
		)
		(stroke
			(width 0)
			(type default)
		)
	)
	(wire
		(pts
			(xy 360.68 162.56) (xy 381 162.56)
		)
		(stroke
			(width 0)
			(type default)
		)
	)
	(wire
		(pts
			(xy 284.48 171.45) (xy 299.72 171.45)
		)
		(stroke
			(width 0)
			(type default)
		)
	)
	(bus
		(pts
			(xy 201.93 120.65) (xy 201.93 123.19)
		)
		(stroke
			(width 0)
			(type default)
		)
	)
	(bus
		(pts
			(xy 201.93 118.11) (xy 201.93 120.65)
		)
		(stroke
			(width 0)
			(type default)
		)
	)
	(bus
		(pts
			(xy 113.03 238.76) (xy 113.03 241.3)
		)
		(stroke
			(width 0)
			(type default)
		)
	)
	(wire
		(pts
			(xy 184.15 116.84) (xy 200.66 116.84)
		)
		(stroke
			(width 0)
			(type default)
		)
	)
	(bus
		(pts
			(xy 370.84 27.94) (xy 384.81 27.94)
		)
		(stroke
			(width 0)
			(type default)
		)
	)
	(wire
		(pts
			(xy 233.68 181.61) (xy 248.92 181.61)
		)
		(stroke
			(width 0)
			(type default)
		)
	)
	(wire
		(pts
			(xy 341.63 162.56) (xy 341.63 163.83)
		)
		(stroke
			(width 0)
			(type default)
		)
	)
	(bus
		(pts
			(xy 43.18 95.25) (xy 43.18 96.52)
		)
		(stroke
			(width 0)
			(type default)
		)
	)
	(wire
		(pts
			(xy 180.34 212.09) (xy 163.83 212.09)
		)
		(stroke
			(width 0)
			(type default)
		)
	)
	(wire
		(pts
			(xy 184.15 137.16) (xy 200.66 137.16)
		)
		(stroke
			(width 0)
			(type default)
		)
	)
	(bus
		(pts
			(xy 181.61 193.04) (xy 181.61 195.58)
		)
		(stroke
			(width 0)
			(type default)
		)
	)
	(bus
		(pts
			(xy 133.35 107.95) (xy 133.35 120.65)
		)
		(stroke
			(width 0)
			(type default)
		)
	)
	(wire
		(pts
			(xy 342.9 62.23) (xy 349.25 62.23)
		)
		(stroke
			(width 0)
			(type default)
		)
	)
	(bus
		(pts
			(xy 43.18 132.08) (xy 43.18 134.62)
		)
		(stroke
			(width 0)
			(type default)
		)
	)
	(wire
		(pts
			(xy 360.68 179.07) (xy 353.06 179.07)
		)
		(stroke
			(width 0)
			(type default)
		)
	)
	(bus
		(pts
			(xy 201.93 138.43) (xy 201.93 140.97)
		)
		(stroke
			(width 0)
			(type default)
		)
	)
	(wire
		(pts
			(xy 298.45 123.19) (xy 279.4 123.19)
		)
		(stroke
			(width 0)
			(type default)
		)
	)
	(wire
		(pts
			(xy 180.34 219.71) (xy 163.83 219.71)
		)
		(stroke
			(width 0)
			(type default)
		)
	)
	(wire
		(pts
			(xy 341.63 163.83) (xy 347.98 163.83)
		)
		(stroke
			(width 0)
			(type default)
		)
	)
	(bus
		(pts
			(xy 181.61 203.2) (xy 181.61 205.74)
		)
		(stroke
			(width 0)
			(type default)
		)
	)
	(bus
		(pts
			(xy 370.84 101.6) (xy 370.84 104.14)
		)
		(stroke
			(width 0)
			(type default)
		)
	)
	(bus
		(pts
			(xy 382.27 179.07) (xy 382.27 181.61)
		)
		(stroke
			(width 0)
			(type default)
		)
	)
	(wire
		(pts
			(xy 342.9 57.15) (xy 349.25 57.15)
		)
		(stroke
			(width 0)
			(type default)
		)
	)
	(wire
		(pts
			(xy 342.9 67.31) (xy 349.25 67.31)
		)
		(stroke
			(width 0)
			(type default)
		)
	)
	(wire
		(pts
			(xy 233.68 176.53) (xy 248.92 176.53)
		)
		(stroke
			(width 0)
			(type default)
		)
	)
	(wire
		(pts
			(xy 369.57 95.25) (xy 336.55 95.25)
		)
		(stroke
			(width 0)
			(type default)
		)
	)
	(wire
		(pts
			(xy 180.34 209.55) (xy 163.83 209.55)
		)
		(stroke
			(width 0)
			(type default)
		)
	)
	(wire
		(pts
			(xy 233.68 184.15) (xy 248.92 184.15)
		)
		(stroke
			(width 0)
			(type default)
		)
	)
	(bus
		(pts
			(xy 382.27 161.29) (xy 382.27 168.91)
		)
		(stroke
			(width 0)
			(type default)
		)
	)
	(bus
		(pts
			(xy 387.35 57.15) (xy 387.35 64.77)
		)
		(stroke
			(width 0)
			(type default)
		)
	)
	(bus
		(pts
			(xy 382.27 194.31) (xy 382.27 201.93)
		)
		(stroke
			(width 0)
			(type default)
		)
	)
	(wire
		(pts
			(xy 361.95 36.83) (xy 361.95 38.1)
		)
		(stroke
			(width 0)
			(type default)
		)
	)
	(bus
		(pts
			(xy 382.27 147.32) (xy 382.27 149.86)
		)
		(stroke
			(width 0)
			(type default)
		)
	)
	(bus
		(pts
			(xy 382.27 214.63) (xy 382.27 212.09)
		)
		(stroke
			(width 0)
			(type default)
		)
	)
	(wire
		(pts
			(xy 360.68 170.18) (xy 360.68 168.91)
		)
		(stroke
			(width 0)
			(type default)
		)
	)
	(wire
		(pts
			(xy 369.57 119.38) (xy 336.55 119.38)
		)
		(stroke
			(width 0)
			(type default)
		)
	)
	(wire
		(pts
			(xy 361.95 55.88) (xy 386.08 55.88)
		)
		(stroke
			(width 0)
			(type default)
		)
	)
	(wire
		(pts
			(xy 361.95 43.18) (xy 386.08 43.18)
		)
		(stroke
			(width 0)
			(type default)
		)
	)
	(bus
		(pts
			(xy 133.35 66.04) (xy 132.08 66.04)
		)
		(stroke
			(width 0)
			(type default)
		)
	)
	(wire
		(pts
			(xy 354.33 67.31) (xy 361.95 67.31)
		)
		(stroke
			(width 0)
			(type default)
		)
	)
	(bus
		(pts
			(xy 382.27 144.78) (xy 382.27 147.32)
		)
		(stroke
			(width 0)
			(type default)
		)
	)
	(wire
		(pts
			(xy 298.45 125.73) (xy 279.4 125.73)
		)
		(stroke
			(width 0)
			(type default)
		)
	)
	(wire
		(pts
			(xy 196.85 44.45) (xy 181.61 44.45)
		)
		(stroke
			(width 0)
			(type default)
		)
	)
	(bus
		(pts
			(xy 201.93 115.57) (xy 201.93 118.11)
		)
		(stroke
			(width 0)
			(type default)
		)
	)
	(bus
		(pts
			(xy 133.35 123.19) (xy 133.35 125.73)
		)
		(stroke
			(width 0)
			(type default)
		)
	)
	(wire
		(pts
			(xy 322.58 63.5) (xy 342.9 63.5)
		)
		(stroke
			(width 0)
			(type default)
		)
	)
	(wire
		(pts
			(xy 342.9 45.72) (xy 342.9 46.99)
		)
		(stroke
			(width 0)
			(type default)
		)
	)
	(bus
		(pts
			(xy 113.03 264.16) (xy 113.03 266.7)
		)
		(stroke
			(width 0)
			(type default)
		)
	)
	(bus
		(pts
			(xy 181.61 208.28) (xy 181.61 210.82)
		)
		(stroke
			(width 0)
			(type default)
		)
	)
	(wire
		(pts
			(xy 298.45 130.81) (xy 279.4 130.81)
		)
		(stroke
			(width 0)
			(type default)
		)
	)
	(wire
		(pts
			(xy 181.61 59.69) (xy 213.36 59.69)
		)
		(stroke
			(width 0)
			(type default)
		)
	)
	(wire
		(pts
			(xy 203.2 43.18) (xy 203.2 46.99)
		)
		(stroke
			(width 0)
			(type default)
		)
	)
	(bus
		(pts
			(xy 382.27 168.91) (xy 382.27 171.45)
		)
		(stroke
			(width 0)
			(type default)
		)
	)
	(bus
		(pts
			(xy 370.84 86.36) (xy 370.84 88.9)
		)
		(stroke
			(width 0)
			(type default)
		)
	)
	(wire
		(pts
			(xy 360.68 214.63) (xy 353.06 214.63)
		)
		(stroke
			(width 0)
			(type default)
		)
	)
	(bus
		(pts
			(xy 181.61 223.52) (xy 181.61 226.06)
		)
		(stroke
			(width 0)
			(type default)
		)
	)
	(bus
		(pts
			(xy 201.93 140.97) (xy 201.93 143.51)
		)
		(stroke
			(width 0)
			(type default)
		)
	)
	(wire
		(pts
			(xy 322.58 43.18) (xy 342.9 43.18)
		)
		(stroke
			(width 0)
			(type default)
		)
	)
	(wire
		(pts
			(xy 360.68 160.02) (xy 381 160.02)
		)
		(stroke
			(width 0)
			(type default)
		)
	)
	(wire
		(pts
			(xy 369.57 127) (xy 336.55 127)
		)
		(stroke
			(width 0)
			(type default)
		)
	)
	(wire
		(pts
			(xy 130.81 39.37) (xy 130.81 64.77)
		)
		(stroke
			(width 0)
			(type default)
		)
	)
	(wire
		(pts
			(xy 29.21 53.34) (xy 29.21 57.15)
		)
		(stroke
			(width 0)
			(type default)
		)
	)
	(wire
		(pts
			(xy 184.15 119.38) (xy 200.66 119.38)
		)
		(stroke
			(width 0)
			(type default)
		)
	)
	(wire
		(pts
			(xy 196.85 49.53) (xy 181.61 49.53)
		)
		(stroke
			(width 0)
			(type default)
		)
	)
	(wire
		(pts
			(xy 284.48 179.07) (xy 299.72 179.07)
		)
		(stroke
			(width 0)
			(type default)
		)
	)
	(bus
		(pts
			(xy 113.03 241.3) (xy 113.03 259.08)
		)
		(stroke
			(width 0)
			(type default)
		)
	)
	(wire
		(pts
			(xy 369.57 121.92) (xy 336.55 121.92)
		)
		(stroke
			(width 0)
			(type default)
		)
	)
	(wire
		(pts
			(xy 97.79 40.64) (xy 107.95 40.64)
		)
		(stroke
			(width 0)
			(type default)
		)
	)
	(bus
		(pts
			(xy 203.2 113.03) (xy 204.47 113.03)
		)
		(stroke
			(width 0)
			(type default)
		)
	)
	(bus
		(pts
			(xy 113.03 259.08) (xy 113.03 261.62)
		)
		(stroke
			(width 0)
			(type default)
		)
	)
	(wire
		(pts
			(xy 180.34 227.33) (xy 163.83 227.33)
		)
		(stroke
			(width 0)
			(type default)
		)
	)
	(wire
		(pts
			(xy 360.68 160.02) (xy 360.68 158.75)
		)
		(stroke
			(width 0)
			(type default)
		)
	)
	(wire
		(pts
			(xy 361.95 33.02) (xy 361.95 34.29)
		)
		(stroke
			(width 0)
			(type default)
		)
	)
	(wire
		(pts
			(xy 341.63 213.36) (xy 341.63 214.63)
		)
		(stroke
			(width 0)
			(type default)
		)
	)
	(wire
		(pts
			(xy 233.68 166.37) (xy 248.92 166.37)
		)
		(stroke
			(width 0)
			(type default)
		)
	)
	(wire
		(pts
			(xy 360.68 151.13) (xy 381 151.13)
		)
		(stroke
			(width 0)
			(type default)
		)
	)
	(wire
		(pts
			(xy 361.95 53.34) (xy 386.08 53.34)
		)
		(stroke
			(width 0)
			(type default)
		)
	)
	(wire
		(pts
			(xy 369.57 114.3) (xy 336.55 114.3)
		)
		(stroke
			(width 0)
			(type default)
		)
	)
	(bus
		(pts
			(xy 181.61 238.76) (xy 181.61 241.3)
		)
		(stroke
			(width 0)
			(type default)
		)
	)
	(bus
		(pts
			(xy 201.93 135.89) (xy 201.93 138.43)
		)
		(stroke
			(width 0)
			(type default)
		)
	)
	(wire
		(pts
			(xy 180.34 207.01) (xy 163.83 207.01)
		)
		(stroke
			(width 0)
			(type default)
		)
	)
	(wire
		(pts
			(xy 341.63 180.34) (xy 341.63 179.07)
		)
		(stroke
			(width 0)
			(type default)
		)
	)
	(wire
		(pts
			(xy 213.36 59.69) (xy 220.98 59.69)
		)
		(stroke
			(width 0)
			(type default)
		)
	)
	(wire
		(pts
			(xy 354.33 57.15) (xy 361.95 57.15)
		)
		(stroke
			(width 0)
			(type default)
		)
	)
	(wire
		(pts
			(xy 360.68 184.15) (xy 353.06 184.15)
		)
		(stroke
			(width 0)
			(type default)
		)
	)
	(bus
		(pts
			(xy 43.18 104.14) (xy 43.18 127)
		)
		(stroke
			(width 0)
			(type default)
		)
	)
	(bus
		(pts
			(xy 198.12 48.26) (xy 198.12 45.72)
		)
		(stroke
			(width 0)
			(type default)
		)
	)
	(wire
		(pts
			(xy 360.68 190.5) (xy 360.68 189.23)
		)
		(stroke
			(width 0)
			(type default)
		)
	)
	(wire
		(pts
			(xy 322.58 34.29) (xy 342.9 34.29)
		)
		(stroke
			(width 0)
			(type default)
		)
	)
	(wire
		(pts
			(xy 360.68 170.18) (xy 381 170.18)
		)
		(stroke
			(width 0)
			(type default)
		)
	)
	(wire
		(pts
			(xy 360.68 168.91) (xy 353.06 168.91)
		)
		(stroke
			(width 0)
			(type default)
		)
	)
	(bus
		(pts
			(xy 382.27 224.79) (xy 382.27 222.25)
		)
		(stroke
			(width 0)
			(type default)
		)
	)
	(wire
		(pts
			(xy 341.63 223.52) (xy 341.63 224.79)
		)
		(stroke
			(width 0)
			(type default)
		)
	)
	(bus
		(pts
			(xy 373.38 85.09) (xy 372.11 85.09)
		)
		(stroke
			(width 0)
			(type default)
		)
	)
	(wire
		(pts
			(xy 360.68 223.52) (xy 381 223.52)
		)
		(stroke
			(width 0)
			(type default)
		)
	)
	(wire
		(pts
			(xy 341.63 204.47) (xy 347.98 204.47)
		)
		(stroke
			(width 0)
			(type default)
		)
	)
	(wire
		(pts
			(xy 341.63 173.99) (xy 347.98 173.99)
		)
		(stroke
			(width 0)
			(type default)
		)
	)
	(wire
		(pts
			(xy 284.48 186.69) (xy 299.72 186.69)
		)
		(stroke
			(width 0)
			(type default)
		)
	)
	(wire
		(pts
			(xy 180.34 224.79) (xy 163.83 224.79)
		)
		(stroke
			(width 0)
			(type default)
		)
	)
	(bus
		(pts
			(xy 181.61 220.98) (xy 181.61 223.52)
		)
		(stroke
			(width 0)
			(type default)
		)
	)
	(wire
		(pts
			(xy 233.68 186.69) (xy 248.92 186.69)
		)
		(stroke
			(width 0)
			(type default)
		)
	)
	(bus
		(pts
			(xy 373.38 105.41) (xy 372.11 105.41)
		)
		(stroke
			(width 0)
			(type default)
		)
	)
	(wire
		(pts
			(xy 325.12 162.56) (xy 341.63 162.56)
		)
		(stroke
			(width 0)
			(type default)
		)
	)
	(wire
		(pts
			(xy 184.15 124.46) (xy 200.66 124.46)
		)
		(stroke
			(width 0)
			(type default)
		)
	)
	(wire
		(pts
			(xy 342.9 33.02) (xy 349.25 33.02)
		)
		(stroke
			(width 0)
			(type default)
		)
	)
	(bus
		(pts
			(xy 198.12 43.18) (xy 198.12 40.64)
		)
		(stroke
			(width 0)
			(type default)
		)
	)
	(wire
		(pts
			(xy 369.57 105.41) (xy 336.55 105.41)
		)
		(stroke
			(width 0)
			(type default)
		)
	)
	(wire
		(pts
			(xy 341.63 170.18) (xy 341.63 168.91)
		)
		(stroke
			(width 0)
			(type default)
		)
	)
	(wire
		(pts
			(xy 361.95 63.5) (xy 386.08 63.5)
		)
		(stroke
			(width 0)
			(type default)
		)
	)
	(wire
		(pts
			(xy 342.9 62.23) (xy 342.9 63.5)
		)
		(stroke
			(width 0)
			(type default)
		)
	)
	(wire
		(pts
			(xy 139.7 35.56) (xy 139.7 44.45)
		)
		(stroke
			(width 0)
			(type default)
		)
	)
	(bus
		(pts
			(xy 181.61 200.66) (xy 181.61 203.2)
		)
		(stroke
			(width 0)
			(type default)
		)
	)
	(bus
		(pts
			(xy 41.91 93.98) (xy 40.64 93.98)
		)
		(stroke
			(width 0)
			(type default)
		)
	)
	(wire
		(pts
			(xy 62.23 38.1) (xy 62.23 35.56)
		)
		(stroke
			(width 0)
			(type default)
		)
	)
	(wire
		(pts
			(xy 111.76 189.23) (xy 130.81 189.23)
		)
		(stroke
			(width 0)
			(type default)
		)
	)
	(wire
		(pts
			(xy 341.63 160.02) (xy 341.63 158.75)
		)
		(stroke
			(width 0)
			(type default)
		)
	)
	(wire
		(pts
			(xy 40.64 44.45) (xy 38.1 44.45)
		)
		(stroke
			(width 0)
			(type default)
		)
	)
	(wire
		(pts
			(xy 361.95 45.72) (xy 361.95 46.99)
		)
		(stroke
			(width 0)
			(type default)
		)
	)
	(wire
		(pts
			(xy 369.57 116.84) (xy 336.55 116.84)
		)
		(stroke
			(width 0)
			(type default)
		)
	)
	(wire
		(pts
			(xy 360.68 209.55) (xy 353.06 209.55)
		)
		(stroke
			(width 0)
			(type default)
		)
	)
	(wire
		(pts
			(xy 284.48 189.23) (xy 299.72 189.23)
		)
		(stroke
			(width 0)
			(type default)
		)
	)
	(wire
		(pts
			(xy 369.57 124.46) (xy 336.55 124.46)
		)
		(stroke
			(width 0)
			(type default)
		)
	)
	(bus
		(pts
			(xy 370.84 110.49) (xy 370.84 113.03)
		)
		(stroke
			(width 0)
			(type default)
		)
	)
	(wire
		(pts
			(xy 341.63 194.31) (xy 347.98 194.31)
		)
		(stroke
			(width 0)
			(type default)
		)
	)
	(wire
		(pts
			(xy 325.12 193.04) (xy 341.63 193.04)
		)
		(stroke
			(width 0)
			(type default)
		)
	)
	(wire
		(pts
			(xy 325.12 213.36) (xy 341.63 213.36)
		)
		(stroke
			(width 0)
			(type default)
		)
	)
	(wire
		(pts
			(xy 134.62 129.54) (xy 151.13 129.54)
		)
		(stroke
			(width 0)
			(type default)
		)
	)
	(wire
		(pts
			(xy 341.63 182.88) (xy 341.63 184.15)
		)
		(stroke
			(width 0)
			(type default)
		)
	)
	(bus
		(pts
			(xy 201.93 114.3) (xy 201.93 115.57)
		)
		(stroke
			(width 0)
			(type default)
		)
	)
	(wire
		(pts
			(xy 213.36 52.07) (xy 213.36 59.69)
		)
		(stroke
			(width 0)
			(type default)
		)
	)
	(bus
		(pts
			(xy 133.35 128.27) (xy 133.35 146.05)
		)
		(stroke
			(width 0)
			(type default)
		)
	)
	(bus
		(pts
			(xy 107.95 189.23) (xy 106.68 189.23)
		)
		(stroke
			(width 0)
			(type default)
		)
	)
	(wire
		(pts
			(xy 322.58 55.88) (xy 342.9 55.88)
		)
		(stroke
			(width 0)
			(type default)
		)
	)
	(wire
		(pts
			(xy 139.7 44.45) (xy 151.13 44.45)
		)
		(stroke
			(width 0)
			(type default)
		)
	)
	(bus
		(pts
			(xy 113.03 237.49) (xy 113.03 238.76)
		)
		(stroke
			(width 0)
			(type default)
		)
	)
	(wire
		(pts
			(xy 44.45 135.89) (xy 60.96 135.89)
		)
		(stroke
			(width 0)
			(type default)
		)
	)
	(wire
		(pts
			(xy 360.68 148.59) (xy 381 148.59)
		)
		(stroke
			(width 0)
			(type default)
		)
	)
	(wire
		(pts
			(xy 130.81 26.67) (xy 130.81 30.48)
		)
		(stroke
			(width 0)
			(type default)
		)
	)
	(bus
		(pts
			(xy 370.84 118.11) (xy 370.84 120.65)
		)
		(stroke
			(width 0)
			(type default)
		)
	)
	(wire
		(pts
			(xy 284.48 166.37) (xy 299.72 166.37)
		)
		(stroke
			(width 0)
			(type default)
		)
	)
	(wire
		(pts
			(xy 360.68 152.4) (xy 353.06 152.4)
		)
		(stroke
			(width 0)
			(type default)
		)
	)
	(wire
		(pts
			(xy 325.12 172.72) (xy 341.63 172.72)
		)
		(stroke
			(width 0)
			(type default)
		)
	)
	(wire
		(pts
			(xy 180.34 201.93) (xy 163.83 201.93)
		)
		(stroke
			(width 0)
			(type default)
		)
	)
	(wire
		(pts
			(xy 184.15 149.86) (xy 200.66 149.86)
		)
		(stroke
			(width 0)
			(type default)
		)
	)
	(wire
		(pts
			(xy 360.68 148.59) (xy 360.68 147.32)
		)
		(stroke
			(width 0)
			(type default)
		)
	)
	(wire
		(pts
			(xy 361.95 45.72) (xy 386.08 45.72)
		)
		(stroke
			(width 0)
			(type default)
		)
	)
	(bus
		(pts
			(xy 133.35 100.33) (xy 133.35 102.87)
		)
		(stroke
			(width 0)
			(type default)
		)
	)
	(bus
		(pts
			(xy 370.84 106.68) (xy 370.84 107.95)
		)
		(stroke
			(width 0)
			(type default)
		)
	)
	(bus
		(pts
			(xy 372.11 105.41) (xy 370.84 106.68)
		)
		(stroke
			(width 0)
			(type default)
		)
	)
	(bus
		(pts
			(xy 111.76 236.22) (xy 113.03 237.49)
		)
		(stroke
			(width 0)
			(type default)
		)
	)
	(wire
		(pts
			(xy 134.62 104.14) (xy 151.13 104.14)
		)
		(stroke
			(width 0)
			(type default)
		)
	)
	(wire
		(pts
			(xy 130.81 39.37) (xy 151.13 39.37)
		)
		(stroke
			(width 0)
			(type default)
		)
	)
	(wire
		(pts
			(xy 298.45 120.65) (xy 279.4 120.65)
		)
		(stroke
			(width 0)
			(type default)
		)
	)
	(bus
		(pts
			(xy 382.27 158.75) (xy 382.27 161.29)
		)
		(stroke
			(width 0)
			(type default)
		)
	)
	(wire
		(pts
			(xy 360.68 194.31) (xy 353.06 194.31)
		)
		(stroke
			(width 0)
			(type default)
		)
	)
	(wire
		(pts
			(xy 114.3 262.89) (xy 130.81 262.89)
		)
		(stroke
			(width 0)
			(type default)
		)
	)
	(wire
		(pts
			(xy 360.68 172.72) (xy 381 172.72)
		)
		(stroke
			(width 0)
			(type default)
		)
	)
	(wire
		(pts
			(xy 233.68 168.91) (xy 248.92 168.91)
		)
		(stroke
			(width 0)
			(type default)
		)
	)
	(wire
		(pts
			(xy 341.63 219.71) (xy 347.98 219.71)
		)
		(stroke
			(width 0)
			(type default)
		)
	)
	(wire
		(pts
			(xy 369.57 100.33) (xy 336.55 100.33)
		)
		(stroke
			(width 0)
			(type default)
		)
	)
	(bus
		(pts
			(xy 181.61 243.84) (xy 181.61 246.38)
		)
		(stroke
			(width 0)
			(type default)
		)
	)
	(bus
		(pts
			(xy 199.39 30.48) (xy 200.66 30.48)
		)
		(stroke
			(width 0)
			(type default)
		)
	)
	(wire
		(pts
			(xy 360.68 163.83) (xy 353.06 163.83)
		)
		(stroke
			(width 0)
			(type default)
		)
	)
	(wire
		(pts
			(xy 342.9 41.91) (xy 349.25 41.91)
		)
		(stroke
			(width 0)
			(type default)
		)
	)
	(wire
		(pts
			(xy 360.68 182.88) (xy 381 182.88)
		)
		(stroke
			(width 0)
			(type default)
		)
	)
	(wire
		(pts
			(xy 361.95 66.04) (xy 361.95 67.31)
		)
		(stroke
			(width 0)
			(type default)
		)
	)
	(wire
		(pts
			(xy 57.15 35.56) (xy 57.15 40.64)
		)
		(stroke
			(width 0)
			(type default)
		)
	)
	(bus
		(pts
			(xy 198.12 45.72) (xy 198.12 43.18)
		)
		(stroke
			(width 0)
			(type default)
		)
	)
	(wire
		(pts
			(xy 360.68 213.36) (xy 381 213.36)
		)
		(stroke
			(width 0)
			(type default)
		)
	)
	(wire
		(pts
			(xy 284.48 176.53) (xy 299.72 176.53)
		)
		(stroke
			(width 0)
			(type default)
		)
	)
	(wire
		(pts
			(xy 341.63 147.32) (xy 347.98 147.32)
		)
		(stroke
			(width 0)
			(type default)
		)
	)
	(wire
		(pts
			(xy 361.95 41.91) (xy 361.95 43.18)
		)
		(stroke
			(width 0)
			(type default)
		)
	)
	(wire
		(pts
			(xy 354.33 41.91) (xy 361.95 41.91)
		)
		(stroke
			(width 0)
			(type default)
		)
	)
	(wire
		(pts
			(xy 184.15 144.78) (xy 200.66 144.78)
		)
		(stroke
			(width 0)
			(type default)
		)
	)
	(bus
		(pts
			(xy 133.35 102.87) (xy 133.35 105.41)
		)
		(stroke
			(width 0)
			(type default)
		)
	)
	(wire
		(pts
			(xy 114.3 267.97) (xy 130.81 267.97)
		)
		(stroke
			(width 0)
			(type default)
		)
	)
	(wire
		(pts
			(xy 360.68 203.2) (xy 360.68 204.47)
		)
		(stroke
			(width 0)
			(type default)
		)
	)
	(wire
		(pts
			(xy 325.12 170.18) (xy 341.63 170.18)
		)
		(stroke
			(width 0)
			(type default)
		)
	)
	(wire
		(pts
			(xy 369.57 87.63) (xy 336.55 87.63)
		)
		(stroke
			(width 0)
			(type default)
		)
	)
	(bus
		(pts
			(xy 132.08 97.79) (xy 133.35 99.06)
		)
		(stroke
			(width 0)
			(type default)
		)
	)
	(wire
		(pts
			(xy 111.76 176.53) (xy 111.76 180.34)
		)
		(stroke
			(width 0)
			(type default)
		)
	)
	(wire
		(pts
			(xy 341.63 190.5) (xy 341.63 189.23)
		)
		(stroke
			(width 0)
			(type default)
		)
	)
	(wire
		(pts
			(xy 322.58 36.83) (xy 342.9 36.83)
		)
		(stroke
			(width 0)
			(type default)
		)
	)
	(wire
		(pts
			(xy 184.15 121.92) (xy 200.66 121.92)
		)
		(stroke
			(width 0)
			(type default)
		)
	)
	(bus
		(pts
			(xy 387.35 41.91) (xy 387.35 44.45)
		)
		(stroke
			(width 0)
			(type default)
		)
	)
	(wire
		(pts
			(xy 322.58 45.72) (xy 342.9 45.72)
		)
		(stroke
			(width 0)
			(type default)
		)
	)
	(bus
		(pts
			(xy 133.35 146.05) (xy 133.35 148.59)
		)
		(stroke
			(width 0)
			(type default)
		)
	)
	(wire
		(pts
			(xy 361.95 34.29) (xy 386.08 34.29)
		)
		(stroke
			(width 0)
			(type default)
		)
	)
	(bus
		(pts
			(xy 43.18 99.06) (xy 43.18 101.6)
		)
		(stroke
			(width 0)
			(type default)
		)
	)
	(wire
		(pts
			(xy 180.34 222.25) (xy 163.83 222.25)
		)
		(stroke
			(width 0)
			(type default)
		)
	)
	(bus
		(pts
			(xy 181.61 226.06) (xy 181.61 238.76)
		)
		(stroke
			(width 0)
			(type default)
		)
	)
	(wire
		(pts
			(xy 298.45 128.27) (xy 279.4 128.27)
		)
		(stroke
			(width 0)
			(type default)
		)
	)
	(wire
		(pts
			(xy 360.68 172.72) (xy 360.68 173.99)
		)
		(stroke
			(width 0)
			(type default)
		)
	)
	(bus
		(pts
			(xy 387.35 29.21) (xy 387.35 33.02)
		)
		(stroke
			(width 0)
			(type default)
		)
	)
	(wire
		(pts
			(xy 180.34 194.31) (xy 163.83 194.31)
		)
		(stroke
			(width 0)
			(type default)
		)
	)
	(bus
		(pts
			(xy 382.27 171.45) (xy 382.27 179.07)
		)
		(stroke
			(width 0)
			(type default)
		)
	)
	(wire
		(pts
			(xy 360.68 200.66) (xy 360.68 199.39)
		)
		(stroke
			(width 0)
			(type default)
		)
	)
	(wire
		(pts
			(xy 44.45 128.27) (xy 60.96 128.27)
		)
		(stroke
			(width 0)
			(type default)
		)
	)
	(wire
		(pts
			(xy 114.3 240.03) (xy 130.81 240.03)
		)
		(stroke
			(width 0)
			(type default)
		)
	)
	(wire
		(pts
			(xy 360.68 162.56) (xy 360.68 163.83)
		)
		(stroke
			(width 0)
			(type default)
		)
	)
	(bus
		(pts
			(xy 382.27 204.47) (xy 382.27 201.93)
		)
		(stroke
			(width 0)
			(type default)
		)
	)
	(wire
		(pts
			(xy 284.48 168.91) (xy 299.72 168.91)
		)
		(stroke
			(width 0)
			(type default)
		)
	)
	(wire
		(pts
			(xy 29.21 44.45) (xy 29.21 48.26)
		)
		(stroke
			(width 0)
			(type default)
		)
	)
	(bus
		(pts
			(xy 181.61 218.44) (xy 181.61 220.98)
		)
		(stroke
			(width 0)
			(type default)
		)
	)
	(label "GTX115.RX1_N"
		(at 367.03 95.25 180)
		(effects
			(font
				(size 1.27 1.27)
			)
			(justify right bottom)
		)
	)
	(label "JTAG.RST"
		(at 184.15 52.07 0)
		(effects
			(font
				(size 1.27 1.27)
			)
			(justify left bottom)
		)
	)
	(label "GTX115.RX3_P"
		(at 367.03 102.87 180)
		(effects
			(font
				(size 1.27 1.27)
			)
			(justify right bottom)
		)
	)
	(label "GTX_RX4_N"
		(at 336.55 105.41 0)
		(effects
			(font
				(size 1.27 1.27)
			)
			(justify left bottom)
		)
	)
	(label "GTX115.RX3_N"
		(at 367.03 105.41 180)
		(effects
			(font
				(size 1.27 1.27)
			)
			(justify right bottom)
		)
	)
	(label "FMC.CLK_DIR"
		(at 298.45 130.81 180)
		(effects
			(font
				(size 1.27 1.27)
			)
			(justify right bottom)
		)
	)
	(label "GTX_RX4_P"
		(at 299.72 173.99 180)
		(effects
			(font
				(size 1.27 1.27)
			)
			(justify right bottom)
		)
	)
	(label "FMC.IO12_P"
		(at 199.39 142.24 180)
		(effects
			(font
				(size 1.27 1.27)
			)
			(justify right bottom)
		)
	)
	(label "GTX_TX2_C_N"
		(at 233.68 166.37 0)
		(effects
			(font
				(size 1.27 1.27)
			)
			(justify left bottom)
		)
	)
	(label "FMC.IO7_P"
		(at 167.64 219.71 0)
		(effects
			(font
				(size 1.27 1.27)
			)
			(justify left bottom)
		)
	)
	(label "GTX_RX5_N"
		(at 299.72 181.61 180)
		(effects
			(font
				(size 1.27 1.27)
			)
			(justify right bottom)
		)
	)
	(label "GTX_TX3_C_N"
		(at 325.12 182.88 0)
		(effects
			(font
				(size 1.27 1.27)
			)
			(justify left bottom)
		)
	)
	(label "GTX_RX5_P"
		(at 299.72 179.07 180)
		(effects
			(font
				(size 1.27 1.27)
			)
			(justify right bottom)
		)
	)
	(label "GTX_TX4_C_P"
		(at 325.12 190.5 0)
		(effects
			(font
				(size 1.27 1.27)
			)
			(justify left bottom)
		)
	)
	(label "GTX_TX0_C_P"
		(at 325.12 148.59 0)
		(effects
			(font
				(size 1.27 1.27)
			)
			(justify left bottom)
		)
	)
	(label "FMC.IO19_P"
		(at 167.64 194.31 0)
		(effects
			(font
				(size 1.27 1.27)
			)
			(justify left bottom)
		)
	)
	(label "FMC.IO11_P"
		(at 199.39 147.32 180)
		(effects
			(font
				(size 1.27 1.27)
			)
			(justify right bottom)
		)
	)
	(label "GTX_TX7_C_P"
		(at 233.68 189.23 0)
		(effects
			(font
				(size 1.27 1.27)
			)
			(justify left bottom)
		)
	)
	(label "FMC.~{PERST}"
		(at 113.03 189.23 0)
		(effects
			(font
				(size 1.27 1.27)
			)
			(justify left bottom)
		)
	)
	(label "GTX_TX5_C_N"
		(at 233.68 181.61 0)
		(effects
			(font
				(size 1.27 1.27)
			)
			(justify left bottom)
		)
	)
	(label "FMC.IO4_P"
		(at 115.57 240.03 0)
		(effects
			(font
				(size 1.27 1.27)
			)
			(justify left bottom)
		)
	)
	(label "FMC.IO8_P"
		(at 167.64 224.79 0)
		(effects
			(font
				(size 1.27 1.27)
			)
			(justify left bottom)
		)
	)
	(label "GTR_REFCLK0_R_N"
		(at 322.58 36.83 0)
		(effects
			(font
				(size 1.27 1.27)
			)
			(justify left bottom)
		)
	)
	(label "GTX115.TX1_P"
		(at 378.46 210.82 180)
		(effects
			(font
				(size 1.27 1.27)
			)
			(justify right bottom)
		)
	)
	(label "GTX116.TX1_N"
		(at 378.46 172.72 180)
		(effects
			(font
				(size 1.27 1.27)
			)
			(justify right bottom)
		)
	)
	(label "GTX_TX2_C_N"
		(at 325.12 172.72 0)
		(effects
			(font
				(size 1.27 1.27)
			)
			(justify left bottom)
		)
	)
	(label "FMC.IO11_N"
		(at 199.39 149.86 180)
		(effects
			(font
				(size 1.27 1.27)
			)
			(justify right bottom)
		)
	)
	(label "GTX_TX5_C_N"
		(at 325.12 203.2 0)
		(effects
			(font
				(size 1.27 1.27)
			)
			(justify left bottom)
		)
	)
	(label "FMC.IO15_P"
		(at 135.89 106.68 0)
		(effects
			(font
				(size 1.27 1.27)
			)
			(justify left bottom)
		)
	)
	(label "GTX_TX7_C_N"
		(at 325.12 223.52 0)
		(effects
			(font
				(size 1.27 1.27)
			)
			(justify left bottom)
		)
	)
	(label "GTX116.RX3_P"
		(at 367.03 124.46 180)
		(effects
			(font
				(size 1.27 1.27)
			)
			(justify right bottom)
		)
	)
	(label "GTX_TX5_C_P"
		(at 325.12 200.66 0)
		(effects
			(font
				(size 1.27 1.27)
			)
			(justify left bottom)
		)
	)
	(label "FMC.IO2_P"
		(at 115.57 265.43 0)
		(effects
			(font
				(size 1.27 1.27)
			)
			(justify left bottom)
		)
	)
	(label "GTX115.TX2_P"
		(at 378.46 200.66 180)
		(effects
			(font
				(size 1.27 1.27)
			)
			(justify right bottom)
		)
	)
	(label "GTX_TX6_C_N"
		(at 233.68 186.69 0)
		(effects
			(font
				(size 1.27 1.27)
			)
			(justify left bottom)
		)
	)
	(label "FMC.IO17_N"
		(at 199.39 119.38 180)
		(effects
			(font
				(size 1.27 1.27)
			)
			(justify right bottom)
		)
	)
	(label "GTX115.RX0_P"
		(at 367.03 87.63 180)
		(effects
			(font
				(size 1.27 1.27)
			)
			(justify right bottom)
		)
	)
	(label "GTR_REFCLK1_R_N"
		(at 322.58 45.72 0)
		(effects
			(font
				(size 1.27 1.27)
			)
			(justify left bottom)
		)
	)
	(label "FMC.IO5_N"
		(at 199.39 124.46 180)
		(effects
			(font
				(size 1.27 1.27)
			)
			(justify right bottom)
		)
	)
	(label "GTX_RX7_P"
		(at 299.72 189.23 180)
		(effects
			(font
				(size 1.27 1.27)
			)
			(justify right bottom)
		)
	)
	(label "FMC.IO22_P"
		(at 167.64 240.03 0)
		(effects
			(font
				(size 1.27 1.27)
			)
			(justify left bottom)
		)
	)
	(label "GTX115.TX1_N"
		(at 378.46 213.36 180)
		(effects
			(font
				(size 1.27 1.27)
			)
			(justify right bottom)
		)
	)
	(label "FMC.IO22_N"
		(at 167.64 242.57 0)
		(effects
			(font
				(size 1.27 1.27)
			)
			(justify left bottom)
		)
	)
	(label "GTX_RX7_P"
		(at 336.55 87.63 0)
		(effects
			(font
				(size 1.27 1.27)
			)
			(justify left bottom)
		)
	)
	(label "GTX115.REFCLK1_P"
		(at 383.54 43.18 180)
		(effects
			(font
				(size 1.27 1.27)
			)
			(justify right bottom)
		)
	)
	(label "FMC.IO19_N"
		(at 167.64 196.85 0)
		(effects
			(font
				(size 1.27 1.27)
			)
			(justify left bottom)
		)
	)
	(label "GTX_RX1_P"
		(at 299.72 158.75 180)
		(effects
			(font
				(size 1.27 1.27)
			)
			(justify right bottom)
		)
	)
	(label "GTX_TX1_C_P"
		(at 325.12 160.02 0)
		(effects
			(font
				(size 1.27 1.27)
			)
			(justify left bottom)
		)
	)
	(label "GTX116.REFCLK1_N"
		(at 383.54 66.04 180)
		(effects
			(font
				(size 1.27 1.27)
			)
			(justify right bottom)
		)
	)
	(label "GTX116.TX2_N"
		(at 378.46 162.56 180)
		(effects
			(font
				(size 1.27 1.27)
			)
			(justify right bottom)
		)
	)
	(label "GTR_REFCLK3_R_N"
		(at 322.58 66.04 0)
		(effects
			(font
				(size 1.27 1.27)
			)
			(justify left bottom)
		)
	)
	(label "GTX_RX2_N"
		(at 299.72 166.37 180)
		(effects
			(font
				(size 1.27 1.27)
			)
			(justify right bottom)
		)
	)
	(label "GTR_REFCLK1_R_P"
		(at 302.26 38.1 180)
		(effects
			(font
				(size 1.27 1.27)
			)
			(justify right bottom)
		)
	)
	(label "GTR_REFCLK2_R_N"
		(at 298.45 123.19 180)
		(effects
			(font
				(size 1.27 1.27)
			)
			(justify right bottom)
		)
	)
	(label "FMC.IO25"
		(at 45.72 128.27 0)
		(effects
			(font
				(size 1.27 1.27)
			)
			(justify left bottom)
		)
	)
	(label "GTX_RX2_P"
		(at 336.55 114.3 0)
		(effects
			(font
				(size 1.27 1.27)
			)
			(justify left bottom)
		)
	)
	(label "GTX115.REFCLK0_P"
		(at 383.54 34.29 180)
		(effects
			(font
				(size 1.27 1.27)
			)
			(justify right bottom)
		)
	)
	(label "FMC.IO1_N"
		(at 167.64 201.93 0)
		(effects
			(font
				(size 1.27 1.27)
			)
			(justify left bottom)
		)
	)
	(label "GTX_TX1_C_N"
		(at 233.68 161.29 0)
		(effects
			(font
				(size 1.27 1.27)
			)
			(justify left bottom)
		)
	)
	(label "GTX_TX2_C_P"
		(at 233.68 163.83 0)
		(effects
			(font
				(size 1.27 1.27)
			)
			(justify left bottom)
		)
	)
	(label "GTX_RX0_P"
		(at 336.55 124.46 0)
		(effects
			(font
				(size 1.27 1.27)
			)
			(justify left bottom)
		)
	)
	(label "GTR_REFCLK2_R_N"
		(at 322.58 55.88 0)
		(effects
			(font
				(size 1.27 1.27)
			)
			(justify left bottom)
		)
	)
	(label "FMC.IO16_N"
		(at 135.89 104.14 0)
		(effects
			(font
				(size 1.27 1.27)
			)
			(justify left bottom)
		)
	)
	(label "GTR_REFCLK3_R_P"
		(at 322.58 63.5 0)
		(effects
			(font
				(size 1.27 1.27)
			)
			(justify left bottom)
		)
	)
	(label "FMC.IO10_P"
		(at 167.64 204.47 0)
		(effects
			(font
				(size 1.27 1.27)
			)
			(justify left bottom)
		)
	)
	(label "GTX115.TX0_N"
		(at 378.46 223.52 180)
		(effects
			(font
				(size 1.27 1.27)
			)
			(justify right bottom)
		)
	)
	(label "FMC.IO9_N"
		(at 167.64 247.65 0)
		(effects
			(font
				(size 1.27 1.27)
			)
			(justify left bottom)
		)
	)
	(label "GTX116.RX2_P"
		(at 367.03 119.38 180)
		(effects
			(font
				(size 1.27 1.27)
			)
			(justify right bottom)
		)
	)
	(label "GTX116.REFCLK0_N"
		(at 383.54 55.88 180)
		(effects
			(font
				(size 1.27 1.27)
			)
			(justify right bottom)
		)
	)
	(label "GTX_RX7_N"
		(at 299.72 191.77 180)
		(effects
			(font
				(size 1.27 1.27)
			)
			(justify right bottom)
		)
	)
	(label "JTAG.TDO"
		(at 184.15 46.99 0)
		(effects
			(font
				(size 1.27 1.27)
			)
			(justify left bottom)
		)
	)
	(label "GTR_REFCLK0_R_P"
		(at 302.26 33.02 180)
		(effects
			(font
				(size 1.27 1.27)
			)
			(justify right bottom)
		)
	)
	(label "FMC.IO20_P"
		(at 45.72 97.79 0)
		(effects
			(font
				(size 1.27 1.27)
			)
			(justify left bottom)
		)
	)
	(label "GTX_RX3_N"
		(at 336.55 111.76 0)
		(effects
			(font
				(size 1.27 1.27)
			)
			(justify left bottom)
		)
	)
	(label "GTX_TX4_C_N"
		(at 325.12 193.04 0)
		(effects
			(font
				(size 1.27 1.27)
			)
			(justify left bottom)
		)
	)
	(label "GTX_RX1_N"
		(at 336.55 121.92 0)
		(effects
			(font
				(size 1.27 1.27)
			)
			(justify left bottom)
		)
	)
	(label "GTX116.TX0_N"
		(at 378.46 182.88 180)
		(effects
			(font
				(size 1.27 1.27)
			)
			(justify right bottom)
		)
	)
	(label "JTAG.TCK"
		(at 184.15 41.91 0)
		(effects
			(font
				(size 1.27 1.27)
			)
			(justify left bottom)
		)
	)
	(label "GTX_TX5_C_P"
		(at 233.68 179.07 0)
		(effects
			(font
				(size 1.27 1.27)
			)
			(justify left bottom)
		)
	)
	(label "GTX115.RX1_P"
		(at 367.03 92.71 180)
		(effects
			(font
				(size 1.27 1.27)
			)
			(justify right bottom)
		)
	)
	(label "JTAG.TMS"
		(at 184.15 49.53 0)
		(effects
			(font
				(size 1.27 1.27)
			)
			(justify left bottom)
		)
	)
	(label "GTX116.RX1_P"
		(at 367.03 114.3 180)
		(effects
			(font
				(size 1.27 1.27)
			)
			(justify right bottom)
		)
	)
	(label "FMC.IO18_P"
		(at 135.89 127 0)
		(effects
			(font
				(size 1.27 1.27)
			)
			(justify left bottom)
		)
	)
	(label "FMC.IO10_N"
		(at 167.64 207.01 0)
		(effects
			(font
				(size 1.27 1.27)
			)
			(justify left bottom)
		)
	)
	(label "FMC.IO3_P"
		(at 115.57 260.35 0)
		(effects
			(font
				(size 1.27 1.27)
			)
			(justify left bottom)
		)
	)
	(label "FMC.IO3_N"
		(at 115.57 262.89 0)
		(effects
			(font
				(size 1.27 1.27)
			)
			(justify left bottom)
		)
	)
	(label "FMC.IO18_N"
		(at 135.89 129.54 0)
		(effects
			(font
				(size 1.27 1.27)
			)
			(justify left bottom)
		)
	)
	(label "GTX_TX3_C_P"
		(at 325.12 180.34 0)
		(effects
			(font
				(size 1.27 1.27)
			)
			(justify left bottom)
		)
	)
	(label "GTX116.REFCLK0_P"
		(at 383.54 53.34 180)
		(effects
			(font
				(size 1.27 1.27)
			)
			(justify right bottom)
		)
	)
	(label "GTX_RX4_N"
		(at 299.72 176.53 180)
		(effects
			(font
				(size 1.27 1.27)
			)
			(justify right bottom)
		)
	)
	(label "GTX_TX2_C_P"
		(at 325.12 170.18 0)
		(effects
			(font
				(size 1.27 1.27)
			)
			(justify left bottom)
		)
	)
	(label "GTR_REFCLK0_R_N"
		(at 302.26 35.56 180)
		(effects
			(font
				(size 1.27 1.27)
			)
			(justify right bottom)
		)
	)
	(label "GTX116.TX2_P"
		(at 378.46 160.02 180)
		(effects
			(font
				(size 1.27 1.27)
			)
			(justify right bottom)
		)
	)
	(label "GTX115.RX2_N"
		(at 367.03 100.33 180)
		(effects
			(font
				(size 1.27 1.27)
			)
			(justify right bottom)
		)
	)
	(label "GTX_RX3_N"
		(at 299.72 171.45 180)
		(effects
			(font
				(size 1.27 1.27)
			)
			(justify right bottom)
		)
	)
	(label "GTX116.TX3_P"
		(at 378.46 148.59 180)
		(effects
			(font
				(size 1.27 1.27)
			)
			(justify right bottom)
		)
	)
	(label "GTX115.TX0_P"
		(at 378.46 220.98 180)
		(effects
			(font
				(size 1.27 1.27)
			)
			(justify right bottom)
		)
	)
	(label "GTX116.TX0_P"
		(at 378.46 180.34 180)
		(effects
			(font
				(size 1.27 1.27)
			)
			(justify right bottom)
		)
	)
	(label "GTX_TX0_C_N"
		(at 325.12 151.13 0)
		(effects
			(font
				(size 1.27 1.27)
			)
			(justify left bottom)
		)
	)
	(label "GTX_TX7_C_N"
		(at 233.68 191.77 0)
		(effects
			(font
				(size 1.27 1.27)
			)
			(justify left bottom)
		)
	)
	(label "GTR_REFCLK0_R_P"
		(at 322.58 34.29 0)
		(effects
			(font
				(size 1.27 1.27)
			)
			(justify left bottom)
		)
	)
	(label "GTX_RX2_N"
		(at 336.55 116.84 0)
		(effects
			(font
				(size 1.27 1.27)
			)
			(justify left bottom)
		)
	)
	(label "GTX116.RX0_P"
		(at 367.03 109.22 180)
		(effects
			(font
				(size 1.27 1.27)
			)
			(justify right bottom)
		)
	)
	(label "GTX_RX6_N"
		(at 336.55 95.25 0)
		(effects
			(font
				(size 1.27 1.27)
			)
			(justify left bottom)
		)
	)
	(label "FMC.IO23_N"
		(at 135.89 149.86 0)
		(effects
			(font
				(size 1.27 1.27)
			)
			(justify left bottom)
		)
	)
	(label "GTX_TX0_C_P"
		(at 233.68 153.67 0)
		(effects
			(font
				(size 1.27 1.27)
			)
			(justify left bottom)
		)
	)
	(label "GTR_REFCLK2_R_P"
		(at 322.58 53.34 0)
		(effects
			(font
				(size 1.27 1.27)
			)
			(justify left bottom)
		)
	)
	(label "FMC.IO14_P"
		(at 45.72 102.87 0)
		(effects
			(font
				(size 1.27 1.27)
			)
			(justify left bottom)
		)
	)
	(label "GTX_RX4_P"
		(at 336.55 102.87 0)
		(effects
			(font
				(size 1.27 1.27)
			)
			(justify left bottom)
		)
	)
	(label "GTX115.TX3_P"
		(at 378.46 190.5 180)
		(effects
			(font
				(size 1.27 1.27)
			)
			(justify right bottom)
		)
	)
	(label "GTX_TX6_C_P"
		(at 325.12 210.82 0)
		(effects
			(font
				(size 1.27 1.27)
			)
			(justify left bottom)
		)
	)
	(label "GTX115.TX3_N"
		(at 378.46 193.04 180)
		(effects
			(font
				(size 1.27 1.27)
			)
			(justify right bottom)
		)
	)
	(label "FMC.IO6_P"
		(at 167.64 209.55 0)
		(effects
			(font
				(size 1.27 1.27)
			)
			(justify left bottom)
		)
	)
	(label "FMC.IO13_N"
		(at 199.39 139.7 180)
		(effects
			(font
				(size 1.27 1.27)
			)
			(justify right bottom)
		)
	)
	(label "GTX_TX6_C_N"
		(at 325.12 213.36 0)
		(effects
			(font
				(size 1.27 1.27)
			)
			(justify left bottom)
		)
	)
	(label "FMC.IO0"
		(at 167.64 255.27 0)
		(effects
			(font
				(size 1.27 1.27)
			)
			(justify left bottom)
		)
	)
	(label "FMC.IO20_N"
		(at 45.72 100.33 0)
		(effects
			(font
				(size 1.27 1.27)
			)
			(justify left bottom)
		)
	)
	(label "GTX_RX0_N"
		(at 336.55 127 0)
		(effects
			(font
				(size 1.27 1.27)
			)
			(justify left bottom)
		)
	)
	(label "GTX116.TX1_P"
		(at 378.46 170.18 180)
		(effects
			(font
				(size 1.27 1.27)
			)
			(justify right bottom)
		)
	)
	(label "FMC.IO5_P"
		(at 199.39 121.92 180)
		(effects
			(font
				(size 1.27 1.27)
			)
			(justify right bottom)
		)
	)
	(label "GTX_RX3_P"
		(at 299.72 168.91 180)
		(effects
			(font
				(size 1.27 1.27)
			)
			(justify right bottom)
		)
	)
	(label "GTX115.RX2_P"
		(at 367.03 97.79 180)
		(effects
			(font
				(size 1.27 1.27)
			)
			(justify right bottom)
		)
	)
	(label "FMC.IO24_P"
		(at 45.72 133.35 0)
		(effects
			(font
				(size 1.27 1.27)
			)
			(justify left bottom)
		)
	)
	(label "GTX_TX1_C_N"
		(at 325.12 162.56 0)
		(effects
			(font
				(size 1.27 1.27)
			)
			(justify left bottom)
		)
	)
	(label "GTX_RX5_N"
		(at 336.55 100.33 0)
		(effects
			(font
				(size 1.27 1.27)
			)
			(justify left bottom)
		)
	)
	(label "GTR_REFCLK1_R_N"
		(at 302.26 40.64 180)
		(effects
			(font
				(size 1.27 1.27)
			)
			(justify right bottom)
		)
	)
	(label "FMC.IO14_N"
		(at 45.72 105.41 0)
		(effects
			(font
				(size 1.27 1.27)
			)
			(justify left bottom)
		)
	)
	(label "FMC.IO16_P"
		(at 135.89 101.6 0)
		(effects
			(font
				(size 1.27 1.27)
			)
			(justify left bottom)
		)
	)
	(label "GTX116.REFCLK1_P"
		(at 383.54 63.5 180)
		(effects
			(font
				(size 1.27 1.27)
			)
			(justify right bottom)
		)
	)
	(label "FMC.IO2_N"
		(at 115.57 267.97 0)
		(effects
			(font
				(size 1.27 1.27)
			)
			(justify left bottom)
		)
	)
	(label "GTX115.REFCLK0_N"
		(at 383.54 36.83 180)
		(effects
			(font
				(size 1.27 1.27)
			)
			(justify right bottom)
		)
	)
	(label "FMC.IO23_P"
		(at 135.89 147.32 0)
		(effects
			(font
				(size 1.27 1.27)
			)
			(justify left bottom)
		)
	)
	(label "FMC.PRSNT_M2C"
		(at 130.81 41.91 270)
		(effects
			(font
				(size 1.27 1.27)
			)
			(justify right bottom)
		)
	)
	(label "GTR_REFCLK3_R_N"
		(at 298.45 128.27 180)
		(effects
			(font
				(size 1.27 1.27)
			)
			(justify right bottom)
		)
	)
	(label "GTX_TX3_C_P"
		(at 233.68 168.91 0)
		(effects
			(font
				(size 1.27 1.27)
			)
			(justify left bottom)
		)
	)
	(label "FMC.IO15_N"
		(at 135.89 109.22 0)
		(effects
			(font
				(size 1.27 1.27)
			)
			(justify left bottom)
		)
	)
	(label "GTR_REFCLK1_R_P"
		(at 322.58 43.18 0)
		(effects
			(font
				(size 1.27 1.27)
			)
			(justify left bottom)
		)
	)
	(label "GTX116.RX1_N"
		(at 367.03 116.84 180)
		(effects
			(font
				(size 1.27 1.27)
			)
			(justify right bottom)
		)
	)
	(label "GTX_RX1_N"
		(at 299.72 161.29 180)
		(effects
			(font
				(size 1.27 1.27)
			)
			(justify right bottom)
		)
	)
	(label "GTX_RX5_P"
		(at 336.55 97.79 0)
		(effects
			(font
				(size 1.27 1.27)
			)
			(justify left bottom)
		)
	)
	(label "GTX_TX1_C_P"
		(at 233.68 158.75 0)
		(effects
			(font
				(size 1.27 1.27)
			)
			(justify left bottom)
		)
	)
	(label "FMC.IO21_P"
		(at 135.89 121.92 0)
		(effects
			(font
				(size 1.27 1.27)
			)
			(justify left bottom)
		)
	)
	(label "GTX_TX3_C_N"
		(at 233.68 171.45 0)
		(effects
			(font
				(size 1.27 1.27)
			)
			(justify left bottom)
		)
	)
	(label "GTX_TX0_C_N"
		(at 233.68 156.21 0)
		(effects
			(font
				(size 1.27 1.27)
			)
			(justify left bottom)
		)
	)
	(label "GTX_TX7_C_P"
		(at 325.12 220.98 0)
		(effects
			(font
				(size 1.27 1.27)
			)
			(justify left bottom)
		)
	)
	(label "GTX115.REFCLK1_N"
		(at 383.54 45.72 180)
		(effects
			(font
				(size 1.27 1.27)
			)
			(justify right bottom)
		)
	)
	(label "GTX_RX0_P"
		(at 299.72 153.67 180)
		(effects
			(font
				(size 1.27 1.27)
			)
			(justify right bottom)
		)
	)
	(label "FMC.IO17_P"
		(at 199.39 116.84 180)
		(effects
			(font
				(size 1.27 1.27)
			)
			(justify right bottom)
		)
	)
	(label "GTX_RX3_P"
		(at 336.55 109.22 0)
		(effects
			(font
				(size 1.27 1.27)
			)
			(justify left bottom)
		)
	)
	(label "FMC.IO9_P"
		(at 167.64 245.11 0)
		(effects
			(font
				(size 1.27 1.27)
			)
			(justify left bottom)
		)
	)
	(label "GTR_REFCLK3_R_P"
		(at 298.45 125.73 180)
		(effects
			(font
				(size 1.27 1.27)
			)
			(justify right bottom)
		)
	)
	(label "GTX_RX2_P"
		(at 299.72 163.83 180)
		(effects
			(font
				(size 1.27 1.27)
			)
			(justify right bottom)
		)
	)
	(label "GTX_RX6_P"
		(at 336.55 92.71 0)
		(effects
			(font
				(size 1.27 1.27)
			)
			(justify left bottom)
		)
	)
	(label "GTX_RX7_N"
		(at 336.55 90.17 0)
		(effects
			(font
				(size 1.27 1.27)
			)
			(justify left bottom)
		)
	)
	(label "FMC.IO21_N"
		(at 135.89 124.46 0)
		(effects
			(font
				(size 1.27 1.27)
			)
			(justify left bottom)
		)
	)
	(label "FMC.IO6_N"
		(at 167.64 212.09 0)
		(effects
			(font
				(size 1.27 1.27)
			)
			(justify left bottom)
		)
	)
	(label "FMC.IO4_N"
		(at 115.57 242.57 0)
		(effects
			(font
				(size 1.27 1.27)
			)
			(justify left bottom)
		)
	)
	(label "GTX_RX0_N"
		(at 299.72 156.21 180)
		(effects
			(font
				(size 1.27 1.27)
			)
			(justify right bottom)
		)
	)
	(label "GTX_TX6_C_P"
		(at 233.68 184.15 0)
		(effects
			(font
				(size 1.27 1.27)
			)
			(justify left bottom)
		)
	)
	(label "GTX116.RX3_N"
		(at 367.03 127 180)
		(effects
			(font
				(size 1.27 1.27)
			)
			(justify right bottom)
		)
	)
	(label "JTAG.TDI"
		(at 184.15 44.45 0)
		(effects
			(font
				(size 1.27 1.27)
			)
			(justify left bottom)
		)
	)
	(label "FMC.IO8_N"
		(at 167.64 227.33 0)
		(effects
			(font
				(size 1.27 1.27)
			)
			(justify left bottom)
		)
	)
	(label "GTX_RX6_N"
		(at 299.72 186.69 180)
		(effects
			(font
				(size 1.27 1.27)
			)
			(justify right bottom)
		)
	)
	(label "GTX115.RX0_N"
		(at 367.03 90.17 180)
		(effects
			(font
				(size 1.27 1.27)
			)
			(justify right bottom)
		)
	)
	(label "GTX_TX4_C_P"
		(at 233.68 173.99 0)
		(effects
			(font
				(size 1.27 1.27)
			)
			(justify left bottom)
		)
	)
	(label "GTX_RX1_P"
		(at 336.55 119.38 0)
		(effects
			(font
				(size 1.27 1.27)
			)
			(justify left bottom)
		)
	)
	(label "FMC.IO12_N"
		(at 199.39 144.78 180)
		(effects
			(font
				(size 1.27 1.27)
			)
			(justify right bottom)
		)
	)
	(label "GTX_TX4_C_N"
		(at 233.68 176.53 0)
		(effects
			(font
				(size 1.27 1.27)
			)
			(justify left bottom)
		)
	)
	(label "GTX_RX6_P"
		(at 299.72 184.15 180)
		(effects
			(font
				(size 1.27 1.27)
			)
			(justify right bottom)
		)
	)
	(label "GTX115.TX2_N"
		(at 378.46 203.2 180)
		(effects
			(font
				(size 1.27 1.27)
			)
			(justify right bottom)
		)
	)
	(label "FMC.IO13_P"
		(at 199.39 137.16 180)
		(effects
			(font
				(size 1.27 1.27)
			)
			(justify right bottom)
		)
	)
	(label "FMC.IO24_N"
		(at 45.72 135.89 0)
		(effects
			(font
				(size 1.27 1.27)
			)
			(justify left bottom)
		)
	)
	(label "GTX116.RX0_N"
		(at 367.03 111.76 180)
		(effects
			(font
				(size 1.27 1.27)
			)
			(justify right bottom)
		)
	)
	(label "FMC.IO7_N"
		(at 167.64 222.25 0)
		(effects
			(font
				(size 1.27 1.27)
			)
			(justify left bottom)
		)
	)
	(label "GTX116.RX2_N"
		(at 367.03 121.92 180)
		(effects
			(font
				(size 1.27 1.27)
			)
			(justify right bottom)
		)
	)
	(label "GTX116.TX3_N"
		(at 378.46 151.13 180)
		(effects
			(font
				(size 1.27 1.27)
			)
			(justify right bottom)
		)
	)
	(label "GTR_REFCLK2_R_P"
		(at 298.45 120.65 180)
		(effects
			(font
				(size 1.27 1.27)
			)
			(justify right bottom)
		)
	)
	(label "FMC.IO1_P"
		(at 167.64 199.39 0)
		(effects
			(font
				(size 1.27 1.27)
			)
			(justify left bottom)
		)
	)
	(global_label "12P0V"
		(shape input)
		(at 40.64 44.45 0)
		(fields_autoplaced yes)
		(effects
			(font
				(size 1.27 1.27)
			)
			(justify left)
		)
		(property "Intersheetrefs" "${INTERSHEET_REFS}"
			(at 48.9513 44.3706 0)
			(effects
				(font
					(size 1.27 1.27)
				)
				(justify left)
				(hide yes)
			)
		)
	)
	(global_label "12P0V"
		(shape input)
		(at 62.23 35.56 90)
		(fields_autoplaced yes)
		(effects
			(font
				(size 1.27 1.27)
			)
			(justify left)
		)
		(property "Intersheetrefs" "${INTERSHEET_REFS}"
			(at 62.1506 27.2487 90)
			(effects
				(font
					(size 1.27 1.27)
				)
				(justify left)
				(hide yes)
			)
		)
	)
	(global_label "FMC.SCL_3V3"
		(shape input)
		(at 220.98 59.69 0)
		(fields_autoplaced yes)
		(effects
			(font
				(size 1.27 1.27)
			)
			(justify left)
		)
		(property "Intersheetrefs" "${INTERSHEET_REFS}"
			(at 236.0647 59.7694 0)
			(effects
				(font
					(size 1.27 1.27)
				)
				(justify left)
				(hide yes)
			)
		)
	)
	(global_label "FMC.SDA_3V3"
		(shape input)
		(at 220.98 57.15 0)
		(fields_autoplaced yes)
		(effects
			(font
				(size 1.27 1.27)
			)
			(justify left)
		)
		(property "Intersheetrefs" "${INTERSHEET_REFS}"
			(at 236.1252 57.2294 0)
			(effects
				(font
					(size 1.27 1.27)
				)
				(justify left)
				(hide yes)
			)
		)
	)
	(hierarchical_label "FMC{FMC-CTRL}"
		(shape bidirectional)
		(at 106.68 189.23 180)
		(effects
			(font
				(size 1.27 1.27)
			)
			(justify right)
		)
	)
	(hierarchical_label "FMC{FMC-IO}"
		(shape bidirectional)
		(at 130.81 97.79 180)
		(effects
			(font
				(size 1.27 1.27)
			)
			(justify right)
		)
	)
	(hierarchical_label "GTX116{MGTX}"
		(shape input)
		(at 369.57 72.39 180)
		(effects
			(font
				(size 1.27 1.27)
			)
			(justify right)
		)
	)
	(hierarchical_label "GTX115{MGTX}"
		(shape input)
		(at 377.19 229.87 180)
		(effects
			(font
				(size 1.27 1.27)
			)
			(justify right)
		)
	)
	(hierarchical_label "FMC{FMC-IO}"
		(shape bidirectional)
		(at 110.49 236.22 180)
		(effects
			(font
				(size 1.27 1.27)
			)
			(justify right)
		)
	)
	(hierarchical_label "GTX115{MGTX}"
		(shape input)
		(at 373.38 85.09 0)
		(effects
			(font
				(size 1.27 1.27)
			)
			(justify left)
		)
	)
	(hierarchical_label "JTAG{JTAG}"
		(shape input)
		(at 200.66 30.48 0)
		(effects
			(font
				(size 1.27 1.27)
			)
			(justify left)
		)
	)
	(hierarchical_label "FMC{FMC-IO}"
		(shape bidirectional)
		(at 203.2 113.03 0)
		(effects
			(font
				(size 1.27 1.27)
			)
			(justify left)
		)
	)
	(hierarchical_label "FMC{FMC-CTRL}"
		(shape bidirectional)
		(at 133.35 66.04 0)
		(effects
			(font
				(size 1.27 1.27)
			)
			(justify left)
		)
	)
	(hierarchical_label "GTX116{MGTX}"
		(shape input)
		(at 379.73 143.51 180)
		(effects
			(font
				(size 1.27 1.27)
			)
			(justify right)
		)
	)
	(hierarchical_label "GTX116{MGTX}"
		(shape input)
		(at 373.38 105.41 0)
		(effects
			(font
				(size 1.27 1.27)
			)
			(justify left)
		)
	)
	(hierarchical_label "FMC{FMC-IO}"
		(shape bidirectional)
		(at 184.15 190.5 0)
		(effects
			(font
				(size 1.27 1.27)
			)
			(justify left)
		)
	)
	(hierarchical_label "FMC{FMC-IO}"
		(shape bidirectional)
		(at 40.64 93.98 180)
		(effects
			(font
				(size 1.27 1.27)
			)
			(justify right)
		)
	)
	(hierarchical_label "GTX115{MGTX}"
		(shape input)
		(at 370.84 27.94 180)
		(effects
			(font
				(size 1.27 1.27)
			)
			(justify right)
		)
	)
	(hierarchical_label "FMC{FMC-CTRL}"
		(shape bidirectional)
		(at 300.99 130.81 0)
		(effects
			(font
				(size 1.27 1.27)
			)
			(justify left)
		)
	)
	(symbol
		(lib_id "antmicroResistors0402:R_33R_0402")
		(at 349.25 46.99 0)
		(unit 1)
		(exclude_from_sim no)
		(in_bom yes)
		(on_board yes)
		(dnp no)
		(property "Reference" "R272"
			(at 356.87 45.72 0)
			(effects
				(font
					(size 1.27 1.27)
				)
			)
		)
		(property "Value" "R_33R_0402"
			(at 369.57 59.69 0)
			(effects
				(font
					(size 1.27 1.27)
					(thickness 0.15)
				)
				(justify left bottom)
				(hide yes)
			)
		)
		(property "Footprint" "antmicro-footprints:R_0402_1005Metric"
			(at 369.57 62.23 0)
			(effects
				(font
					(size 1.27 1.27)
					(thickness 0.15)
				)
				(justify left bottom)
				(hide yes)
			)
		)
		(property "Datasheet" "https://www.bourns.com/docs/product-datasheets/cr.pdf"
			(at 369.57 64.77 0)
			(effects
				(font
					(size 1.27 1.27)
					(thickness 0.15)
				)
				(justify left bottom)
				(hide yes)
			)
		)
		(property "Description" ""
			(at 349.25 46.99 0)
			(effects
				(font
					(size 1.27 1.27)
				)
			)
		)
		(property "Manufacturer" "Bourns"
			(at 369.57 69.85 0)
			(effects
				(font
					(size 1.27 1.27)
					(thickness 0.15)
				)
				(justify left bottom)
				(hide yes)
			)
		)
		(property "MPN" "CR0402-FX-33R0GLF"
			(at 369.57 67.31 0)
			(effects
				(font
					(size 1.27 1.27)
					(thickness 0.15)
				)
				(justify left bottom)
				(hide yes)
			)
		)
		(property "Val" "33R"
			(at 347.345 45.72 0)
			(effects
				(font
					(size 1.27 1.27)
					(thickness 0.15)
				)
			)
		)
		(property "License" "Apache-2.0"
			(at 369.57 72.39 0)
			(effects
				(font
					(size 1.27 1.27)
					(thickness 0.15)
				)
				(justify left bottom)
				(hide yes)
			)
		)
		(property "Author" "Antmicro"
			(at 369.57 74.93 0)
			(effects
				(font
					(size 1.27 1.27)
					(thickness 0.15)
				)
				(justify left bottom)
				(hide yes)
			)
		)
		(property "Tolerance" "1%"
			(at 369.57 57.15 0)
			(effects
				(font
					(size 1.27 1.27)
				)
				(justify left bottom)
				(hide yes)
			)
		)
		(pin "1"
		)
		(pin "2"
		)
		(instances
			(project "k410t-devboard"
				(path ""
					(reference "R272")
					(unit 1)
				)
			)
		)
	)
	(symbol
		(lib_id "antmicroCapacitors0402:C_100n_0402")
		(at 353.06 189.23 180)
		(unit 1)
		(exclude_from_sim no)
		(in_bom yes)
		(on_board yes)
		(dnp no)
		(property "Reference" "C306"
			(at 355.6 187.96 0)
			(effects
				(font
					(size 1.27 1.27)
				)
			)
		)
		(property "Value" "C_100n_0402"
			(at 332.74 179.07 0)
			(effects
				(font
					(size 1.27 1.27)
					(thickness 0.15)
				)
				(justify left bottom)
				(hide yes)
			)
		)
		(property "Footprint" "antmicro-footprints:C_0402_1005Metric"
			(at 332.74 176.53 0)
			(effects
				(font
					(size 1.27 1.27)
					(thickness 0.15)
				)
				(justify left bottom)
				(hide yes)
			)
		)
		(property "Datasheet" "https://www.murata.com/products/productdetail?partno=GRM155R61H104KE14%23"
			(at 332.74 173.99 0)
			(effects
				(font
					(size 1.27 1.27)
					(thickness 0.15)
				)
				(justify left bottom)
				(hide yes)
			)
		)
		(property "Description" ""
			(at 353.06 189.23 0)
			(effects
				(font
					(size 1.27 1.27)
				)
			)
		)
		(property "Manufacturer" "Murata"
			(at 332.74 168.91 0)
			(effects
				(font
					(size 1.27 1.27)
					(thickness 0.15)
				)
				(justify left bottom)
				(hide yes)
			)
		)
		(property "MPN" "GRM155R61H104KE14D"
			(at 332.74 171.45 0)
			(effects
				(font
					(size 1.27 1.27)
					(thickness 0.15)
				)
				(justify left bottom)
				(hide yes)
			)
		)
		(property "Val" "100n"
			(at 346.075 187.96 0)
			(effects
				(font
					(size 1.27 1.27)
					(thickness 0.15)
				)
			)
		)
		(property "License" "Apache-2.0"
			(at 332.74 166.37 0)
			(effects
				(font
					(size 1.27 1.27)
					(thickness 0.15)
				)
				(justify left bottom)
				(hide yes)
			)
		)
		(property "Author" "Antmicro"
			(at 332.74 163.83 0)
			(effects
				(font
					(size 1.27 1.27)
					(thickness 0.15)
				)
				(justify left bottom)
				(hide yes)
			)
		)
		(property "Voltage" "50V"
			(at 332.74 161.29 0)
			(effects
				(font
					(size 1.27 1.27)
				)
				(justify left bottom)
				(hide yes)
			)
		)
		(property "Dielectric" "X5R"
			(at 332.74 158.75 0)
			(effects
				(font
					(size 1.27 1.27)
				)
				(justify left bottom)
				(hide yes)
			)
		)
		(pin "1"
		)
		(pin "2"
		)
		(instances
			(project "k410t-devboard"
				(path ""
					(reference "C306")
					(unit 1)
				)
			)
		)
	)
	(symbol
		(lib_id "antmicroB2BConnectors:ASP-184329-01_CUSTOM_mounting_holes")
		(at 151.13 36.83 0)
		(unit 2)
		(exclude_from_sim no)
		(in_bom yes)
		(on_board yes)
		(dnp no)
		(fields_autoplaced yes)
		(property "Reference" "J18"
			(at 166.37 25.4 0)
			(effects
				(font
					(size 1.27 1.27)
					(thickness 0.15)
				)
			)
		)
		(property "Value" "ASP-184329-01_mounting_holes"
			(at 166.37 28.575 0)
			(effects
				(font
					(size 1.27 1.27)
					(thickness 0.15)
				)
				(hide yes)
			)
		)
		(property "Footprint" "antmicro-footprints:ASP-184329-01_mounting_holes"
			(at 196.85 48.26 0)
			(effects
				(font
					(size 1.27 1.27)
					(thickness 0.15)
				)
				(justify left bottom)
				(hide yes)
			)
		)
		(property "Datasheet" "https://www.mouser.com/datasheet/2/527/asp_184329_01_mkt-2854128.pdf"
			(at 196.85 50.8 0)
			(effects
				(font
					(size 1.27 1.27)
					(thickness 0.15)
				)
				(justify left bottom)
				(hide yes)
			)
		)
		(property "Description" ""
			(at 151.13 36.83 0)
			(effects
				(font
					(size 1.27 1.27)
				)
			)
		)
		(property "Manufacturer" "Samtec"
			(at 196.85 53.34 0)
			(effects
				(font
					(size 1.27 1.27)
					(thickness 0.15)
				)
				(justify left bottom)
				(hide yes)
			)
		)
		(property "MPN" "ASP-184329-01"
			(at 166.37 27.94 0)
			(effects
				(font
					(size 1.27 1.27)
					(thickness 0.15)
				)
			)
		)
		(property "Author" "Antmicro"
			(at 196.85 58.42 0)
			(effects
				(font
					(size 1.27 1.27)
					(thickness 0.15)
				)
				(justify left bottom)
				(hide yes)
			)
		)
		(property "License" "Apache-2.0"
			(at 196.85 60.96 0)
			(effects
				(font
					(size 1.27 1.27)
					(thickness 0.15)
				)
				(justify left bottom)
				(hide yes)
			)
		)
		(pin "C30"
		)
		(pin "C31"
		)
		(pin "C34"
		)
		(pin "D01"
		)
		(pin "D29"
		)
		(pin "D30"
		)
		(pin "D31"
		)
		(pin "D33"
		)
		(pin "D34"
		)
		(pin "D35"
		)
		(pin "F01"
		)
		(pin "H02"
		)
		(pin "Z01"
		)
		(pin "J20"
		)
		(pin "J23"
		)
		(pin "J26"
		)
		(pin "J29"
		)
		(pin "J32"
		)
		(pin "J05"
		)
		(pin "J08"
		)
		(pin "J11"
		)
		(pin "J14"
		)
		(pin "J17"
		)
		(pin "H12"
		)
		(pin "H15"
		)
		(pin "H03"
		)
		(pin "H06"
		)
		(pin "H09"
		)
		(pin "H39"
		)
		(pin "H40"
		)
		(pin "J01"
		)
		(pin "J04"
		)
		(pin "H27"
		)
		(pin "H30"
		)
		(pin "H33"
		)
		(pin "H36"
		)
		(pin "J35"
		)
		(pin "J38"
		)
		(pin "J39"
		)
		(pin "J40"
		)
		(pin "K01"
		)
		(pin "K02"
		)
		(pin "K03"
		)
		(pin "K06"
		)
		(pin "K09"
		)
		(pin "K12"
		)
		(pin "K15"
		)
		(pin "K18"
		)
		(pin "K21"
		)
		(pin "A01"
		)
		(pin "K24"
		)
		(pin "K27"
		)
		(pin "K30"
		)
		(pin "K33"
		)
		(pin "K36"
		)
		(pin "K39"
		)
		(pin "K40"
		)
		(pin "L01"
		)
		(pin "L02"
		)
		(pin "L03"
		)
		(pin "L06"
		)
		(pin "L07"
		)
		(pin "L10"
		)
		(pin "L11"
		)
		(pin "L14"
		)
		(pin "L15"
		)
		(pin "L18"
		)
		(pin "L19"
		)
		(pin "L22"
		)
		(pin "L23"
		)
		(pin "L26"
		)
		(pin "L27"
		)
		(pin "L30"
		)
		(pin "L31"
		)
		(pin "L32"
		)
		(pin "L33"
		)
		(pin "L34"
		)
		(pin "L35"
		)
		(pin "L36"
		)
		(pin "L37"
		)
		(pin "L38"
		)
		(pin "Z34"
		)
		(pin "Z35"
		)
		(pin "Z38"
		)
		(pin "Z39"
		)
		(pin "Z40"
		)
		(pin "H18"
		)
		(pin "H21"
		)
		(pin "H24"
		)
		(pin "A04"
		)
		(pin "A05"
		)
		(pin "A08"
		)
		(pin "A09"
		)
		(pin "A12"
		)
		(pin "A13"
		)
		(pin "A16"
		)
		(pin "A17"
		)
		(pin "A20"
		)
		(pin "A21"
		)
		(pin "A24"
		)
		(pin "A25"
		)
		(pin "A28"
		)
		(pin "A29"
		)
		(pin "A32"
		)
		(pin "A33"
		)
		(pin "A36"
		)
		(pin "A37"
		)
		(pin "A40"
		)
		(pin "B02"
		)
		(pin "B03"
		)
		(pin "B06"
		)
		(pin "B07"
		)
		(pin "B10"
		)
		(pin "B11"
		)
		(pin "B14"
		)
		(pin "B15"
		)
		(pin "B18"
		)
		(pin "B19"
		)
		(pin "B22"
		)
		(pin "B23"
		)
		(pin "B26"
		)
		(pin "B27"
		)
		(pin "B30"
		)
		(pin "B31"
		)
		(pin "B34"
		)
		(pin "B35"
		)
		(pin "B38"
		)
		(pin "B39"
		)
		(pin "B40"
		)
		(pin "C01"
		)
		(pin "C04"
		)
		(pin "C05"
		)
		(pin "C08"
		)
		(pin "C09"
		)
		(pin "C12"
		)
		(pin "C13"
		)
		(pin "C16"
		)
		(pin "C17"
		)
		(pin "C20"
		)
		(pin "C21"
		)
		(pin "C24"
		)
		(pin "C25"
		)
		(pin "C28"
		)
		(pin "C29"
		)
		(pin "C32"
		)
		(pin "C33"
		)
		(pin "C35"
		)
		(pin "C36"
		)
		(pin "C37"
		)
		(pin "C38"
		)
		(pin "C39"
		)
		(pin "C40"
		)
		(pin "D02"
		)
		(pin "D03"
		)
		(pin "D06"
		)
		(pin "D07"
		)
		(pin "D10"
		)
		(pin "D13"
		)
		(pin "D16"
		)
		(pin "D19"
		)
		(pin "D22"
		)
		(pin "D25"
		)
		(pin "D28"
		)
		(pin "D32"
		)
		(pin "D36"
		)
		(pin "D37"
		)
		(pin "D38"
		)
		(pin "D39"
		)
		(pin "D40"
		)
		(pin "E01"
		)
		(pin "E04"
		)
		(pin "E05"
		)
		(pin "E08"
		)
		(pin "E11"
		)
		(pin "E14"
		)
		(pin "E17"
		)
		(pin "E20"
		)
		(pin "E23"
		)
		(pin "E26"
		)
		(pin "E29"
		)
		(pin "E32"
		)
		(pin "E35"
		)
		(pin "E38"
		)
		(pin "E39"
		)
		(pin "E40"
		)
		(pin "F02"
		)
		(pin "F03"
		)
		(pin "F06"
		)
		(pin "F09"
		)
		(pin "F12"
		)
		(pin "F15"
		)
		(pin "F18"
		)
		(pin "F21"
		)
		(pin "F24"
		)
		(pin "F27"
		)
		(pin "F30"
		)
		(pin "F33"
		)
		(pin "F36"
		)
		(pin "F39"
		)
		(pin "F40"
		)
		(pin "G01"
		)
		(pin "G04"
		)
		(pin "G05"
		)
		(pin "G08"
		)
		(pin "G11"
		)
		(pin "G14"
		)
		(pin "G17"
		)
		(pin "G20"
		)
		(pin "G23"
		)
		(pin "G26"
		)
		(pin "G29"
		)
		(pin "G32"
		)
		(pin "G35"
		)
		(pin "G38"
		)
		(pin "G39"
		)
		(pin "G40"
		)
		(pin "H01"
		)
		(pin "L39"
		)
		(pin "L40"
		)
		(pin "M01"
		)
		(pin "M04"
		)
		(pin "M05"
		)
		(pin "M08"
		)
		(pin "M09"
		)
		(pin "M12"
		)
		(pin "M13"
		)
		(pin "M16"
		)
		(pin "M17"
		)
		(pin "M20"
		)
		(pin "M21"
		)
		(pin "M24"
		)
		(pin "M25"
		)
		(pin "M28"
		)
		(pin "M29"
		)
		(pin "M32"
		)
		(pin "M33"
		)
		(pin "M36"
		)
		(pin "M37"
		)
		(pin "M40"
		)
		(pin "Y01"
		)
		(pin "Y04"
		)
		(pin "Y05"
		)
		(pin "Y08"
		)
		(pin "Y09"
		)
		(pin "Y12"
		)
		(pin "Y13"
		)
		(pin "Y16"
		)
		(pin "Y17"
		)
		(pin "Y20"
		)
		(pin "Y21"
		)
		(pin "Y24"
		)
		(pin "Y25"
		)
		(pin "Y28"
		)
		(pin "Y29"
		)
		(pin "Y32"
		)
		(pin "Y33"
		)
		(pin "Y36"
		)
		(pin "Y37"
		)
		(pin "Y40"
		)
		(pin "Z02"
		)
		(pin "Z03"
		)
		(pin "Z06"
		)
		(pin "Z07"
		)
		(pin "Z10"
		)
		(pin "Z11"
		)
		(pin "Z14"
		)
		(pin "Z15"
		)
		(pin "Z18"
		)
		(pin "Z19"
		)
		(pin "Z22"
		)
		(pin "Z23"
		)
		(pin "Z26"
		)
		(pin "Z27"
		)
		(pin "Z30"
		)
		(pin "Z31"
		)
		(pin "M19"
		)
		(pin "M22"
		)
		(pin "M23"
		)
		(pin "M26"
		)
		(pin "M27"
		)
		(pin "M30"
		)
		(pin "M31"
		)
		(pin "M34"
		)
		(pin "M35"
		)
		(pin "M38"
		)
		(pin "C10"
		)
		(pin "C11"
		)
		(pin "C14"
		)
		(pin "C15"
		)
		(pin "C18"
		)
		(pin "C19"
		)
		(pin "C22"
		)
		(pin "C23"
		)
		(pin "C26"
		)
		(pin "C27"
		)
		(pin "D08"
		)
		(pin "D09"
		)
		(pin "D11"
		)
		(pin "D12"
		)
		(pin "D14"
		)
		(pin "D15"
		)
		(pin "D17"
		)
		(pin "D18"
		)
		(pin "D20"
		)
		(pin "D21"
		)
		(pin "D23"
		)
		(pin "D24"
		)
		(pin "D26"
		)
		(pin "D27"
		)
		(pin "G06"
		)
		(pin "G07"
		)
		(pin "G09"
		)
		(pin "G10"
		)
		(pin "G12"
		)
		(pin "G13"
		)
		(pin "G15"
		)
		(pin "G16"
		)
		(pin "G18"
		)
		(pin "G19"
		)
		(pin "G21"
		)
		(pin "G22"
		)
		(pin "G24"
		)
		(pin "G25"
		)
		(pin "G27"
		)
		(pin "G28"
		)
		(pin "G30"
		)
		(pin "G31"
		)
		(pin "G33"
		)
		(pin "G34"
		)
		(pin "G36"
		)
		(pin "G37"
		)
		(pin "H07"
		)
		(pin "H08"
		)
		(pin "H10"
		)
		(pin "H11"
		)
		(pin "H13"
		)
		(pin "H14"
		)
		(pin "H16"
		)
		(pin "H17"
		)
		(pin "H19"
		)
		(pin "H20"
		)
		(pin "H22"
		)
		(pin "H23"
		)
		(pin "H25"
		)
		(pin "H26"
		)
		(pin "H28"
		)
		(pin "H29"
		)
		(pin "H31"
		)
		(pin "H32"
		)
		(pin "H34"
		)
		(pin "H35"
		)
		(pin "H37"
		)
		(pin "H38"
		)
		(pin "E02"
		)
		(pin "E03"
		)
		(pin "E06"
		)
		(pin "E07"
		)
		(pin "E09"
		)
		(pin "E10"
		)
		(pin "E12"
		)
		(pin "E13"
		)
		(pin "E15"
		)
		(pin "E16"
		)
		(pin "E18"
		)
		(pin "E19"
		)
		(pin "F04"
		)
		(pin "F05"
		)
		(pin "F07"
		)
		(pin "F08"
		)
		(pin "F10"
		)
		(pin "F11"
		)
		(pin "F13"
		)
		(pin "F14"
		)
		(pin "F16"
		)
		(pin "F17"
		)
		(pin "F19"
		)
		(pin "F20"
		)
		(pin "J06"
		)
		(pin "J07"
		)
		(pin "J09"
		)
		(pin "J10"
		)
		(pin "J12"
		)
		(pin "J13"
		)
		(pin "J15"
		)
		(pin "J16"
		)
		(pin "J18"
		)
		(pin "J19"
		)
		(pin "J21"
		)
		(pin "J22"
		)
		(pin "K07"
		)
		(pin "K08"
		)
		(pin "K10"
		)
		(pin "K11"
		)
		(pin "K13"
		)
		(pin "K14"
		)
		(pin "K16"
		)
		(pin "K17"
		)
		(pin "K19"
		)
		(pin "K20"
		)
		(pin "K22"
		)
		(pin "K23"
		)
		(pin "E21"
		)
		(pin "E22"
		)
		(pin "E24"
		)
		(pin "E25"
		)
		(pin "E27"
		)
		(pin "E28"
		)
		(pin "E30"
		)
		(pin "E31"
		)
		(pin "E33"
		)
		(pin "E34"
		)
		(pin "E36"
		)
		(pin "E37"
		)
		(pin "F22"
		)
		(pin "F23"
		)
		(pin "F25"
		)
		(pin "F26"
		)
		(pin "F28"
		)
		(pin "F29"
		)
		(pin "F31"
		)
		(pin "F32"
		)
		(pin "F34"
		)
		(pin "F35"
		)
		(pin "F37"
		)
		(pin "F38"
		)
		(pin "J24"
		)
		(pin "J25"
		)
		(pin "J27"
		)
		(pin "J28"
		)
		(pin "J30"
		)
		(pin "J31"
		)
		(pin "J33"
		)
		(pin "J34"
		)
		(pin "J36"
		)
		(pin "J37"
		)
		(pin "K25"
		)
		(pin "K26"
		)
		(pin "K28"
		)
		(pin "K29"
		)
		(pin "K31"
		)
		(pin "K32"
		)
		(pin "K34"
		)
		(pin "K35"
		)
		(pin "K37"
		)
		(pin "K38"
		)
		(pin "B01"
		)
		(pin "G02"
		)
		(pin "G03"
		)
		(pin "H04"
		)
		(pin "H05"
		)
		(pin "J02"
		)
		(pin "J03"
		)
		(pin "K04"
		)
		(pin "K05"
		)
		(pin "B20"
		)
		(pin "B21"
		)
		(pin "D04"
		)
		(pin "D05"
		)
		(pin "L04"
		)
		(pin "L05"
		)
		(pin "L08"
		)
		(pin "L09"
		)
		(pin "L12"
		)
		(pin "L13"
		)
		(pin "L16"
		)
		(pin "L17"
		)
		(pin "L20"
		)
		(pin "L21"
		)
		(pin "L24"
		)
		(pin "L25"
		)
		(pin "L28"
		)
		(pin "L29"
		)
		(pin "Z20"
		)
		(pin "Z21"
		)
		(pin "A02"
		)
		(pin "A03"
		)
		(pin "A06"
		)
		(pin "A07"
		)
		(pin "A10"
		)
		(pin "A11"
		)
		(pin "A14"
		)
		(pin "A15"
		)
		(pin "A18"
		)
		(pin "A19"
		)
		(pin "A22"
		)
		(pin "A23"
		)
		(pin "A26"
		)
		(pin "A27"
		)
		(pin "A30"
		)
		(pin "A31"
		)
		(pin "A34"
		)
		(pin "A35"
		)
		(pin "A38"
		)
		(pin "A39"
		)
		(pin "B04"
		)
		(pin "B05"
		)
		(pin "B08"
		)
		(pin "B09"
		)
		(pin "B12"
		)
		(pin "B13"
		)
		(pin "B16"
		)
		(pin "B17"
		)
		(pin "B24"
		)
		(pin "B25"
		)
		(pin "B28"
		)
		(pin "B29"
		)
		(pin "B32"
		)
		(pin "B33"
		)
		(pin "B36"
		)
		(pin "B37"
		)
		(pin "C02"
		)
		(pin "C03"
		)
		(pin "C06"
		)
		(pin "C07"
		)
		(pin "M02"
		)
		(pin "M03"
		)
		(pin "M06"
		)
		(pin "M07"
		)
		(pin "M10"
		)
		(pin "M11"
		)
		(pin "M14"
		)
		(pin "M15"
		)
		(pin "M18"
		)
		(pin "M39"
		)
		(pin "Y02"
		)
		(pin "Y03"
		)
		(pin "Y06"
		)
		(pin "Y07"
		)
		(pin "Y10"
		)
		(pin "Y11"
		)
		(pin "Y14"
		)
		(pin "Y15"
		)
		(pin "Y18"
		)
		(pin "Y19"
		)
		(pin "Y22"
		)
		(pin "Y23"
		)
		(pin "Y26"
		)
		(pin "Y27"
		)
		(pin "Y30"
		)
		(pin "Y31"
		)
		(pin "Y34"
		)
		(pin "Y35"
		)
		(pin "Y38"
		)
		(pin "Y39"
		)
		(pin "Z04"
		)
		(pin "Z05"
		)
		(pin "Z08"
		)
		(pin "Z09"
		)
		(pin "Z12"
		)
		(pin "Z13"
		)
		(pin "Z16"
		)
		(pin "Z17"
		)
		(pin "Z24"
		)
		(pin "Z25"
		)
		(pin "Z28"
		)
		(pin "Z29"
		)
		(pin "Z32"
		)
		(pin "Z33"
		)
		(pin "Z36"
		)
		(pin "Z37"
		)
		(instances
			(project "k410t-devboard"
				(path ""
					(reference "J18")
					(unit 2)
				)
			)
		)
	)
	(symbol
		(lib_id "antmicroB2BConnectors:ASP-184329-01_CUSTOM_mounting_holes")
		(at 151.13 91.44 0)
		(unit 4)
		(exclude_from_sim no)
		(in_bom yes)
		(on_board yes)
		(dnp no)
		(fields_autoplaced yes)
		(property "Reference" "J18"
			(at 167.64 77.47 0)
			(effects
				(font
					(size 1.27 1.27)
					(thickness 0.15)
				)
			)
		)
		(property "Value" "ASP-184329-01_mounting_holes"
			(at 167.64 81.28 0)
			(effects
				(font
					(size 1.27 1.27)
					(thickness 0.15)
				)
				(hide yes)
			)
		)
		(property "Footprint" "antmicro-footprints:ASP-184329-01_mounting_holes"
			(at 196.85 102.87 0)
			(effects
				(font
					(size 1.27 1.27)
					(thickness 0.15)
				)
				(justify left bottom)
				(hide yes)
			)
		)
		(property "Datasheet" "https://www.mouser.com/datasheet/2/527/asp_184329_01_mkt-2854128.pdf"
			(at 196.85 105.41 0)
			(effects
				(font
					(size 1.27 1.27)
					(thickness 0.15)
				)
				(justify left bottom)
				(hide yes)
			)
		)
		(property "Description" ""
			(at 151.13 91.44 0)
			(effects
				(font
					(size 1.27 1.27)
				)
			)
		)
		(property "Manufacturer" "Samtec"
			(at 196.85 107.95 0)
			(effects
				(font
					(size 1.27 1.27)
					(thickness 0.15)
				)
				(justify left bottom)
				(hide yes)
			)
		)
		(property "MPN" "ASP-184329-01"
			(at 167.64 80.01 0)
			(effects
				(font
					(size 1.27 1.27)
					(thickness 0.15)
				)
			)
		)
		(property "Author" "Antmicro"
			(at 196.85 113.03 0)
			(effects
				(font
					(size 1.27 1.27)
					(thickness 0.15)
				)
				(justify left bottom)
				(hide yes)
			)
		)
		(property "License" "Apache-2.0"
			(at 196.85 115.57 0)
			(effects
				(font
					(size 1.27 1.27)
					(thickness 0.15)
				)
				(justify left bottom)
				(hide yes)
			)
		)
		(pin "E02"
		)
		(pin "E03"
		)
		(pin "E06"
		)
		(pin "E07"
		)
		(pin "E09"
		)
		(pin "E10"
		)
		(pin "E12"
		)
		(pin "E13"
		)
		(pin "E15"
		)
		(pin "E16"
		)
		(pin "E18"
		)
		(pin "E19"
		)
		(pin "F04"
		)
		(pin "F05"
		)
		(pin "F07"
		)
		(pin "F08"
		)
		(pin "F10"
		)
		(pin "F11"
		)
		(pin "F13"
		)
		(pin "F14"
		)
		(pin "F16"
		)
		(pin "F17"
		)
		(pin "F19"
		)
		(pin "F20"
		)
		(pin "J06"
		)
		(pin "J07"
		)
		(pin "J09"
		)
		(pin "J10"
		)
		(pin "J12"
		)
		(pin "J13"
		)
		(pin "J15"
		)
		(pin "J16"
		)
		(pin "J18"
		)
		(pin "J19"
		)
		(pin "J21"
		)
		(pin "J22"
		)
		(pin "K07"
		)
		(pin "K08"
		)
		(pin "K10"
		)
		(pin "K11"
		)
		(pin "K13"
		)
		(pin "K14"
		)
		(pin "K16"
		)
		(pin "K17"
		)
		(pin "K19"
		)
		(pin "K20"
		)
		(pin "K22"
		)
		(pin "K23"
		)
		(pin "B30"
		)
		(pin "A01"
		)
		(pin "A04"
		)
		(pin "A05"
		)
		(pin "A08"
		)
		(pin "A09"
		)
		(pin "A12"
		)
		(pin "A13"
		)
		(pin "A16"
		)
		(pin "A17"
		)
		(pin "A20"
		)
		(pin "A21"
		)
		(pin "A24"
		)
		(pin "A25"
		)
		(pin "A28"
		)
		(pin "A29"
		)
		(pin "A32"
		)
		(pin "A33"
		)
		(pin "A36"
		)
		(pin "A37"
		)
		(pin "A40"
		)
		(pin "B02"
		)
		(pin "B03"
		)
		(pin "B06"
		)
		(pin "B07"
		)
		(pin "B10"
		)
		(pin "B11"
		)
		(pin "B14"
		)
		(pin "B15"
		)
		(pin "B18"
		)
		(pin "B19"
		)
		(pin "B22"
		)
		(pin "B23"
		)
		(pin "B26"
		)
		(pin "B27"
		)
		(pin "B31"
		)
		(pin "B34"
		)
		(pin "B35"
		)
		(pin "B38"
		)
		(pin "B39"
		)
		(pin "B40"
		)
		(pin "C01"
		)
		(pin "C04"
		)
		(pin "C05"
		)
		(pin "C08"
		)
		(pin "C09"
		)
		(pin "C12"
		)
		(pin "C13"
		)
		(pin "C16"
		)
		(pin "C17"
		)
		(pin "C20"
		)
		(pin "C21"
		)
		(pin "C24"
		)
		(pin "C25"
		)
		(pin "C28"
		)
		(pin "C29"
		)
		(pin "C32"
		)
		(pin "C33"
		)
		(pin "C35"
		)
		(pin "C36"
		)
		(pin "C37"
		)
		(pin "C38"
		)
		(pin "C39"
		)
		(pin "C40"
		)
		(pin "D02"
		)
		(pin "D03"
		)
		(pin "D06"
		)
		(pin "D07"
		)
		(pin "D10"
		)
		(pin "D13"
		)
		(pin "D16"
		)
		(pin "D19"
		)
		(pin "D22"
		)
		(pin "D25"
		)
		(pin "D28"
		)
		(pin "D32"
		)
		(pin "D36"
		)
		(pin "D37"
		)
		(pin "D38"
		)
		(pin "D39"
		)
		(pin "D40"
		)
		(pin "E01"
		)
		(pin "E04"
		)
		(pin "E05"
		)
		(pin "E08"
		)
		(pin "E11"
		)
		(pin "E14"
		)
		(pin "E17"
		)
		(pin "E20"
		)
		(pin "E23"
		)
		(pin "E26"
		)
		(pin "E29"
		)
		(pin "E32"
		)
		(pin "E35"
		)
		(pin "E38"
		)
		(pin "E39"
		)
		(pin "E40"
		)
		(pin "F02"
		)
		(pin "F03"
		)
		(pin "F06"
		)
		(pin "F09"
		)
		(pin "F12"
		)
		(pin "F15"
		)
		(pin "F18"
		)
		(pin "F21"
		)
		(pin "F24"
		)
		(pin "F27"
		)
		(pin "F30"
		)
		(pin "F33"
		)
		(pin "F36"
		)
		(pin "F39"
		)
		(pin "F40"
		)
		(pin "G01"
		)
		(pin "G04"
		)
		(pin "G05"
		)
		(pin "G08"
		)
		(pin "G11"
		)
		(pin "G14"
		)
		(pin "G17"
		)
		(pin "G20"
		)
		(pin "G23"
		)
		(pin "G26"
		)
		(pin "G29"
		)
		(pin "G32"
		)
		(pin "G35"
		)
		(pin "G38"
		)
		(pin "G39"
		)
		(pin "G40"
		)
		(pin "H01"
		)
		(pin "Z34"
		)
		(pin "Z35"
		)
		(pin "Z38"
		)
		(pin "Z39"
		)
		(pin "Z40"
		)
		(pin "C30"
		)
		(pin "H03"
		)
		(pin "H06"
		)
		(pin "H09"
		)
		(pin "H12"
		)
		(pin "H15"
		)
		(pin "H18"
		)
		(pin "H21"
		)
		(pin "H24"
		)
		(pin "H27"
		)
		(pin "H30"
		)
		(pin "H33"
		)
		(pin "H36"
		)
		(pin "H39"
		)
		(pin "H40"
		)
		(pin "J01"
		)
		(pin "J04"
		)
		(pin "J05"
		)
		(pin "J08"
		)
		(pin "J11"
		)
		(pin "J14"
		)
		(pin "J17"
		)
		(pin "J20"
		)
		(pin "J23"
		)
		(pin "J26"
		)
		(pin "J29"
		)
		(pin "J32"
		)
		(pin "J35"
		)
		(pin "J38"
		)
		(pin "J39"
		)
		(pin "J40"
		)
		(pin "K01"
		)
		(pin "K02"
		)
		(pin "K03"
		)
		(pin "K06"
		)
		(pin "K09"
		)
		(pin "K12"
		)
		(pin "K15"
		)
		(pin "K18"
		)
		(pin "K21"
		)
		(pin "K24"
		)
		(pin "K27"
		)
		(pin "K30"
		)
		(pin "K33"
		)
		(pin "K36"
		)
		(pin "K39"
		)
		(pin "K40"
		)
		(pin "L01"
		)
		(pin "L02"
		)
		(pin "L03"
		)
		(pin "L06"
		)
		(pin "L07"
		)
		(pin "L10"
		)
		(pin "L11"
		)
		(pin "L14"
		)
		(pin "L15"
		)
		(pin "L18"
		)
		(pin "L19"
		)
		(pin "L22"
		)
		(pin "L23"
		)
		(pin "L26"
		)
		(pin "L27"
		)
		(pin "L30"
		)
		(pin "L31"
		)
		(pin "L32"
		)
		(pin "L33"
		)
		(pin "L34"
		)
		(pin "L35"
		)
		(pin "L36"
		)
		(pin "L37"
		)
		(pin "L38"
		)
		(pin "L39"
		)
		(pin "L40"
		)
		(pin "M01"
		)
		(pin "M04"
		)
		(pin "M05"
		)
		(pin "M08"
		)
		(pin "M09"
		)
		(pin "M12"
		)
		(pin "M13"
		)
		(pin "M16"
		)
		(pin "M17"
		)
		(pin "M20"
		)
		(pin "M21"
		)
		(pin "M24"
		)
		(pin "M25"
		)
		(pin "M28"
		)
		(pin "M29"
		)
		(pin "M32"
		)
		(pin "M33"
		)
		(pin "M36"
		)
		(pin "M37"
		)
		(pin "M40"
		)
		(pin "Y01"
		)
		(pin "Y04"
		)
		(pin "Y05"
		)
		(pin "Y08"
		)
		(pin "Y09"
		)
		(pin "Y12"
		)
		(pin "Y13"
		)
		(pin "Y16"
		)
		(pin "Y17"
		)
		(pin "Y20"
		)
		(pin "Y21"
		)
		(pin "Y24"
		)
		(pin "Y25"
		)
		(pin "Y28"
		)
		(pin "Y29"
		)
		(pin "Y32"
		)
		(pin "Y33"
		)
		(pin "Y36"
		)
		(pin "Y37"
		)
		(pin "Y40"
		)
		(pin "Z02"
		)
		(pin "Z03"
		)
		(pin "Z06"
		)
		(pin "Z07"
		)
		(pin "Z10"
		)
		(pin "Z11"
		)
		(pin "Z14"
		)
		(pin "Z15"
		)
		(pin "Z18"
		)
		(pin "Z19"
		)
		(pin "Z22"
		)
		(pin "Z23"
		)
		(pin "Z26"
		)
		(pin "Z27"
		)
		(pin "Z30"
		)
		(pin "Z31"
		)
		(pin "M19"
		)
		(pin "M22"
		)
		(pin "M23"
		)
		(pin "M26"
		)
		(pin "M27"
		)
		(pin "M30"
		)
		(pin "M31"
		)
		(pin "M34"
		)
		(pin "M35"
		)
		(pin "M38"
		)
		(pin "C31"
		)
		(pin "C34"
		)
		(pin "D01"
		)
		(pin "D29"
		)
		(pin "D30"
		)
		(pin "D31"
		)
		(pin "D33"
		)
		(pin "D34"
		)
		(pin "D35"
		)
		(pin "F01"
		)
		(pin "H02"
		)
		(pin "Z01"
		)
		(pin "C10"
		)
		(pin "C11"
		)
		(pin "C14"
		)
		(pin "C15"
		)
		(pin "C18"
		)
		(pin "C19"
		)
		(pin "C22"
		)
		(pin "C23"
		)
		(pin "C26"
		)
		(pin "C27"
		)
		(pin "D08"
		)
		(pin "D09"
		)
		(pin "D11"
		)
		(pin "D12"
		)
		(pin "D14"
		)
		(pin "D15"
		)
		(pin "D17"
		)
		(pin "D18"
		)
		(pin "D20"
		)
		(pin "D21"
		)
		(pin "D23"
		)
		(pin "D24"
		)
		(pin "D26"
		)
		(pin "D27"
		)
		(pin "G06"
		)
		(pin "G07"
		)
		(pin "G09"
		)
		(pin "G10"
		)
		(pin "G12"
		)
		(pin "G13"
		)
		(pin "G15"
		)
		(pin "G16"
		)
		(pin "G18"
		)
		(pin "G19"
		)
		(pin "G21"
		)
		(pin "G22"
		)
		(pin "G24"
		)
		(pin "G25"
		)
		(pin "G27"
		)
		(pin "G28"
		)
		(pin "G30"
		)
		(pin "G31"
		)
		(pin "G33"
		)
		(pin "G34"
		)
		(pin "G36"
		)
		(pin "G37"
		)
		(pin "H07"
		)
		(pin "H08"
		)
		(pin "H10"
		)
		(pin "H11"
		)
		(pin "H13"
		)
		(pin "H14"
		)
		(pin "H16"
		)
		(pin "H17"
		)
		(pin "H19"
		)
		(pin "H20"
		)
		(pin "H22"
		)
		(pin "H23"
		)
		(pin "H25"
		)
		(pin "H26"
		)
		(pin "H28"
		)
		(pin "H29"
		)
		(pin "H31"
		)
		(pin "H32"
		)
		(pin "H34"
		)
		(pin "H35"
		)
		(pin "H37"
		)
		(pin "H38"
		)
		(pin "E21"
		)
		(pin "E22"
		)
		(pin "E24"
		)
		(pin "E25"
		)
		(pin "E27"
		)
		(pin "E28"
		)
		(pin "E30"
		)
		(pin "E31"
		)
		(pin "E33"
		)
		(pin "E34"
		)
		(pin "E36"
		)
		(pin "E37"
		)
		(pin "F22"
		)
		(pin "F23"
		)
		(pin "F25"
		)
		(pin "F26"
		)
		(pin "F28"
		)
		(pin "F29"
		)
		(pin "F31"
		)
		(pin "F32"
		)
		(pin "F34"
		)
		(pin "F35"
		)
		(pin "F37"
		)
		(pin "F38"
		)
		(pin "J24"
		)
		(pin "J25"
		)
		(pin "J27"
		)
		(pin "J28"
		)
		(pin "J30"
		)
		(pin "J31"
		)
		(pin "J33"
		)
		(pin "J34"
		)
		(pin "J36"
		)
		(pin "J37"
		)
		(pin "K25"
		)
		(pin "K26"
		)
		(pin "K28"
		)
		(pin "K29"
		)
		(pin "K31"
		)
		(pin "K32"
		)
		(pin "K34"
		)
		(pin "K35"
		)
		(pin "K37"
		)
		(pin "K38"
		)
		(pin "B01"
		)
		(pin "G02"
		)
		(pin "G03"
		)
		(pin "H04"
		)
		(pin "H05"
		)
		(pin "J02"
		)
		(pin "J03"
		)
		(pin "K04"
		)
		(pin "K05"
		)
		(pin "B20"
		)
		(pin "B21"
		)
		(pin "D04"
		)
		(pin "D05"
		)
		(pin "L04"
		)
		(pin "L05"
		)
		(pin "L08"
		)
		(pin "L09"
		)
		(pin "L12"
		)
		(pin "L13"
		)
		(pin "L16"
		)
		(pin "L17"
		)
		(pin "L20"
		)
		(pin "L21"
		)
		(pin "L24"
		)
		(pin "L25"
		)
		(pin "L28"
		)
		(pin "L29"
		)
		(pin "Z20"
		)
		(pin "Z21"
		)
		(pin "A02"
		)
		(pin "A03"
		)
		(pin "A06"
		)
		(pin "A07"
		)
		(pin "A10"
		)
		(pin "A11"
		)
		(pin "A14"
		)
		(pin "A15"
		)
		(pin "A18"
		)
		(pin "A19"
		)
		(pin "A22"
		)
		(pin "A23"
		)
		(pin "A26"
		)
		(pin "A27"
		)
		(pin "A30"
		)
		(pin "A31"
		)
		(pin "A34"
		)
		(pin "A35"
		)
		(pin "A38"
		)
		(pin "A39"
		)
		(pin "B04"
		)
		(pin "B05"
		)
		(pin "B08"
		)
		(pin "B09"
		)
		(pin "B12"
		)
		(pin "B13"
		)
		(pin "B16"
		)
		(pin "B17"
		)
		(pin "B24"
		)
		(pin "B25"
		)
		(pin "B28"
		)
		(pin "B29"
		)
		(pin "B32"
		)
		(pin "B33"
		)
		(pin "B36"
		)
		(pin "B37"
		)
		(pin "C02"
		)
		(pin "C03"
		)
		(pin "C06"
		)
		(pin "C07"
		)
		(pin "M02"
		)
		(pin "M03"
		)
		(pin "M06"
		)
		(pin "M07"
		)
		(pin "M10"
		)
		(pin "M11"
		)
		(pin "M14"
		)
		(pin "M15"
		)
		(pin "M18"
		)
		(pin "M39"
		)
		(pin "Y02"
		)
		(pin "Y03"
		)
		(pin "Y06"
		)
		(pin "Y07"
		)
		(pin "Y10"
		)
		(pin "Y11"
		)
		(pin "Y14"
		)
		(pin "Y15"
		)
		(pin "Y18"
		)
		(pin "Y19"
		)
		(pin "Y22"
		)
		(pin "Y23"
		)
		(pin "Y26"
		)
		(pin "Y27"
		)
		(pin "Y30"
		)
		(pin "Y31"
		)
		(pin "Y34"
		)
		(pin "Y35"
		)
		(pin "Y38"
		)
		(pin "Y39"
		)
		(pin "Z04"
		)
		(pin "Z05"
		)
		(pin "Z08"
		)
		(pin "Z09"
		)
		(pin "Z12"
		)
		(pin "Z13"
		)
		(pin "Z16"
		)
		(pin "Z17"
		)
		(pin "Z24"
		)
		(pin "Z25"
		)
		(pin "Z28"
		)
		(pin "Z29"
		)
		(pin "Z32"
		)
		(pin "Z33"
		)
		(pin "Z36"
		)
		(pin "Z37"
		)
		(instances
			(project "k410t-devboard"
				(path ""
					(reference "J18")
					(unit 4)
				)
			)
		)
	)
	(symbol
		(lib_id "antmicropower:+3.3V")
		(at 111.76 176.53 0)
		(unit 1)
		(exclude_from_sim no)
		(in_bom yes)
		(on_board yes)
		(dnp no)
		(property "Reference" "#PWR0509"
			(at 111.76 180.34 0)
			(effects
				(font
					(size 1.27 1.27)
				)
				(hide yes)
			)
		)
		(property "Value" "+3V3"
			(at 111.76 172.974 0)
			(effects
				(font
					(size 1.27 1.27)
				)
			)
		)
		(property "Footprint" ""
			(at 111.76 176.53 0)
			(effects
				(font
					(size 1.27 1.27)
				)
				(hide yes)
			)
		)
		(property "Datasheet" ""
			(at 111.76 176.53 0)
			(effects
				(font
					(size 1.27 1.27)
				)
				(hide yes)
			)
		)
		(property "Description" ""
			(at 111.76 176.53 0)
			(effects
				(font
					(size 1.27 1.27)
				)
			)
		)
		(pin "1"
		)
		(instances
			(project "k410t-devboard"
				(path ""
					(reference "#PWR0509")
					(unit 1)
				)
			)
		)
	)
	(symbol
		(lib_id "antmicroTestPoints:TP_0.75mm_SMD")
		(at 105.41 35.56 90)
		(unit 1)
		(exclude_from_sim no)
		(in_bom yes)
		(on_board yes)
		(dnp no)
		(property "Reference" "TP1"
			(at 102.87 32.385 90)
			(effects
				(font
					(size 1.27 1.27)
				)
			)
		)
		(property "Value" "TP_0.75mm_SMD"
			(at 113.03 20.32 0)
			(effects
				(font
					(size 1.27 1.27)
					(thickness 0.15)
				)
				(justify left bottom)
				(hide yes)
			)
		)
		(property "Footprint" "antmicro-footprints:TP_SMD_0.75mm"
			(at 115.57 20.32 0)
			(effects
				(font
					(size 1.27 1.27)
					(thickness 0.15)
				)
				(justify left bottom)
				(hide yes)
			)
		)
		(property "Datasheet" ""
			(at 118.11 20.32 0)
			(effects
				(font
					(size 1.27 1.27)
					(thickness 0.15)
				)
				(justify left bottom)
				(hide yes)
			)
		)
		(property "Description" ""
			(at 105.41 35.56 0)
			(effects
				(font
					(size 1.27 1.27)
				)
			)
		)
		(property "MPN" ""
			(at 105.41 35.56 0)
			(effects
				(font
					(size 1.27 1.27)
				)
				(hide yes)
			)
		)
		(property "Manufacturer" ""
			(at 105.41 35.56 0)
			(effects
				(font
					(size 1.27 1.27)
				)
				(hide yes)
			)
		)
		(property "Author" "Antmicro"
			(at 120.65 20.32 0)
			(effects
				(font
					(size 1.27 1.27)
					(thickness 0.15)
				)
				(justify left bottom)
				(hide yes)
			)
		)
		(property "License" "Apache-2.0"
			(at 123.19 20.32 0)
			(effects
				(font
					(size 1.27 1.27)
					(thickness 0.15)
				)
				(justify left bottom)
				(hide yes)
			)
		)
		(pin "1"
		)
		(instances
			(project "k410t-devboard"
				(path ""
					(reference "TP1")
					(unit 1)
				)
			)
		)
	)
	(symbol
		(lib_id "antmicroTestPoints:TP_0.75mm_SMD")
		(at 107.95 35.56 90)
		(unit 1)
		(exclude_from_sim no)
		(in_bom yes)
		(on_board yes)
		(dnp no)
		(property "Reference" "TP2"
			(at 110.49 32.385 90)
			(effects
				(font
					(size 1.27 1.27)
				)
			)
		)
		(property "Value" "TP_0.75mm_SMD"
			(at 115.57 20.32 0)
			(effects
				(font
					(size 1.27 1.27)
					(thickness 0.15)
				)
				(justify left bottom)
				(hide yes)
			)
		)
		(property "Footprint" "antmicro-footprints:TP_SMD_0.75mm"
			(at 118.11 20.32 0)
			(effects
				(font
					(size 1.27 1.27)
					(thickness 0.15)
				)
				(justify left bottom)
				(hide yes)
			)
		)
		(property "Datasheet" ""
			(at 120.65 20.32 0)
			(effects
				(font
					(size 1.27 1.27)
					(thickness 0.15)
				)
				(justify left bottom)
				(hide yes)
			)
		)
		(property "Description" ""
			(at 107.95 35.56 0)
			(effects
				(font
					(size 1.27 1.27)
				)
			)
		)
		(property "MPN" ""
			(at 107.95 35.56 0)
			(effects
				(font
					(size 1.27 1.27)
				)
				(hide yes)
			)
		)
		(property "Manufacturer" ""
			(at 107.95 35.56 0)
			(effects
				(font
					(size 1.27 1.27)
				)
				(hide yes)
			)
		)
		(property "Author" "Antmicro"
			(at 123.19 20.32 0)
			(effects
				(font
					(size 1.27 1.27)
					(thickness 0.15)
				)
				(justify left bottom)
				(hide yes)
			)
		)
		(property "License" "Apache-2.0"
			(at 125.73 20.32 0)
			(effects
				(font
					(size 1.27 1.27)
					(thickness 0.15)
				)
				(justify left bottom)
				(hide yes)
			)
		)
		(pin "1"
		)
		(instances
			(project "k410t-devboard"
				(path ""
					(reference "TP2")
					(unit 1)
				)
			)
		)
	)
	(symbol
		(lib_id "antmicropower:VDC")
		(at 29.21 29.21 0)
		(unit 1)
		(exclude_from_sim no)
		(in_bom yes)
		(on_board yes)
		(dnp no)
		(property "Reference" "#PWR0348"
			(at 29.21 31.75 0)
			(effects
				(font
					(size 1.27 1.27)
				)
				(hide yes)
			)
		)
		(property "Value" "VDC"
			(at 29.21 22.86 0)
			(effects
				(font
					(size 1.27 1.27)
				)
			)
		)
		(property "Footprint" ""
			(at 29.21 29.21 0)
			(effects
				(font
					(size 1.27 1.27)
				)
				(hide yes)
			)
		)
		(property "Datasheet" ""
			(at 29.21 29.21 0)
			(effects
				(font
					(size 1.27 1.27)
				)
				(hide yes)
			)
		)
		(property "Description" ""
			(at 29.21 29.21 0)
			(effects
				(font
					(size 1.27 1.27)
				)
			)
		)
		(pin "1"
		)
		(instances
			(project "k410t-devboard"
				(path ""
					(reference "#PWR0348")
					(unit 1)
				)
			)
		)
	)
	(symbol
		(lib_id "antmicroResistors0402:R_33R_0402")
		(at 349.25 33.02 0)
		(unit 1)
		(exclude_from_sim no)
		(in_bom yes)
		(on_board yes)
		(dnp no)
		(property "Reference" "R269"
			(at 356.87 31.75 0)
			(effects
				(font
					(size 1.27 1.27)
				)
			)
		)
		(property "Value" "R_33R_0402"
			(at 369.57 45.72 0)
			(effects
				(font
					(size 1.27 1.27)
					(thickness 0.15)
				)
				(justify left bottom)
				(hide yes)
			)
		)
		(property "Footprint" "antmicro-footprints:R_0402_1005Metric"
			(at 369.57 48.26 0)
			(effects
				(font
					(size 1.27 1.27)
					(thickness 0.15)
				)
				(justify left bottom)
				(hide yes)
			)
		)
		(property "Datasheet" "https://www.bourns.com/docs/product-datasheets/cr.pdf"
			(at 369.57 50.8 0)
			(effects
				(font
					(size 1.27 1.27)
					(thickness 0.15)
				)
				(justify left bottom)
				(hide yes)
			)
		)
		(property "Description" ""
			(at 349.25 33.02 0)
			(effects
				(font
					(size 1.27 1.27)
				)
			)
		)
		(property "Manufacturer" "Bourns"
			(at 369.57 55.88 0)
			(effects
				(font
					(size 1.27 1.27)
					(thickness 0.15)
				)
				(justify left bottom)
				(hide yes)
			)
		)
		(property "MPN" "CR0402-FX-33R0GLF"
			(at 369.57 53.34 0)
			(effects
				(font
					(size 1.27 1.27)
					(thickness 0.15)
				)
				(justify left bottom)
				(hide yes)
			)
		)
		(property "Val" "33R"
			(at 347.345 31.75 0)
			(effects
				(font
					(size 1.27 1.27)
					(thickness 0.15)
				)
			)
		)
		(property "License" "Apache-2.0"
			(at 369.57 58.42 0)
			(effects
				(font
					(size 1.27 1.27)
					(thickness 0.15)
				)
				(justify left bottom)
				(hide yes)
			)
		)
		(property "Author" "Antmicro"
			(at 369.57 60.96 0)
			(effects
				(font
					(size 1.27 1.27)
					(thickness 0.15)
				)
				(justify left bottom)
				(hide yes)
			)
		)
		(property "Tolerance" "1%"
			(at 369.57 43.18 0)
			(effects
				(font
					(size 1.27 1.27)
				)
				(justify left bottom)
				(hide yes)
			)
		)
		(pin "1"
		)
		(pin "2"
		)
		(instances
			(project "k410t-devboard"
				(path ""
					(reference "R269")
					(unit 1)
				)
			)
		)
	)
	(symbol
		(lib_id "antmicroB2BConnectors:ASP-184329-01_CUSTOM_mounting_holes")
		(at 248.92 153.67 0)
		(unit 8)
		(exclude_from_sim no)
		(in_bom yes)
		(on_board yes)
		(dnp no)
		(fields_autoplaced yes)
		(property "Reference" "J18"
			(at 266.7 139.7 0)
			(effects
				(font
					(size 1.27 1.27)
					(thickness 0.15)
				)
			)
		)
		(property "Value" "ASP-184329-01_mounting_holes"
			(at 266.7 142.875 0)
			(effects
				(font
					(size 1.27 1.27)
					(thickness 0.15)
				)
				(hide yes)
			)
		)
		(property "Footprint" "antmicro-footprints:ASP-184329-01_mounting_holes"
			(at 294.64 165.1 0)
			(effects
				(font
					(size 1.27 1.27)
					(thickness 0.15)
				)
				(justify left bottom)
				(hide yes)
			)
		)
		(property "Datasheet" "https://www.mouser.com/datasheet/2/527/asp_184329_01_mkt-2854128.pdf"
			(at 294.64 167.64 0)
			(effects
				(font
					(size 1.27 1.27)
					(thickness 0.15)
				)
				(justify left bottom)
				(hide yes)
			)
		)
		(property "Description" ""
			(at 248.92 153.67 0)
			(effects
				(font
					(size 1.27 1.27)
				)
			)
		)
		(property "Manufacturer" "Samtec"
			(at 294.64 170.18 0)
			(effects
				(font
					(size 1.27 1.27)
					(thickness 0.15)
				)
				(justify left bottom)
				(hide yes)
			)
		)
		(property "MPN" "ASP-184329-01"
			(at 266.7 142.24 0)
			(effects
				(font
					(size 1.27 1.27)
					(thickness 0.15)
				)
			)
		)
		(property "Author" "Antmicro"
			(at 294.64 175.26 0)
			(effects
				(font
					(size 1.27 1.27)
					(thickness 0.15)
				)
				(justify left bottom)
				(hide yes)
			)
		)
		(property "License" "Apache-2.0"
			(at 294.64 177.8 0)
			(effects
				(font
					(size 1.27 1.27)
					(thickness 0.15)
				)
				(justify left bottom)
				(hide yes)
			)
		)
		(pin "A02"
		)
		(pin "A03"
		)
		(pin "A06"
		)
		(pin "A07"
		)
		(pin "A10"
		)
		(pin "A11"
		)
		(pin "A14"
		)
		(pin "A15"
		)
		(pin "A18"
		)
		(pin "A19"
		)
		(pin "A22"
		)
		(pin "A23"
		)
		(pin "A26"
		)
		(pin "A27"
		)
		(pin "A30"
		)
		(pin "A31"
		)
		(pin "A34"
		)
		(pin "A35"
		)
		(pin "A38"
		)
		(pin "A39"
		)
		(pin "B04"
		)
		(pin "B05"
		)
		(pin "B08"
		)
		(pin "B09"
		)
		(pin "B12"
		)
		(pin "B13"
		)
		(pin "B16"
		)
		(pin "B17"
		)
		(pin "B24"
		)
		(pin "B25"
		)
		(pin "B28"
		)
		(pin "B29"
		)
		(pin "B32"
		)
		(pin "B33"
		)
		(pin "B36"
		)
		(pin "B37"
		)
		(pin "C02"
		)
		(pin "C03"
		)
		(pin "C06"
		)
		(pin "C07"
		)
		(pin "M02"
		)
		(pin "M03"
		)
		(pin "M06"
		)
		(pin "M07"
		)
		(pin "M10"
		)
		(pin "M11"
		)
		(pin "M14"
		)
		(pin "M15"
		)
		(pin "M18"
		)
		(pin "M19"
		)
		(pin "M22"
		)
		(pin "M23"
		)
		(pin "M26"
		)
		(pin "M27"
		)
		(pin "M30"
		)
		(pin "M31"
		)
		(pin "M34"
		)
		(pin "M35"
		)
		(pin "M38"
		)
		(pin "M39"
		)
		(pin "Y02"
		)
		(pin "Y03"
		)
		(pin "Y06"
		)
		(pin "Y07"
		)
		(pin "Y10"
		)
		(pin "Y11"
		)
		(pin "Y14"
		)
		(pin "Y15"
		)
		(pin "Y18"
		)
		(pin "Y19"
		)
		(pin "Y22"
		)
		(pin "Y23"
		)
		(pin "Y26"
		)
		(pin "Y27"
		)
		(pin "Y30"
		)
		(pin "Y31"
		)
		(pin "Y34"
		)
		(pin "Y35"
		)
		(pin "Y38"
		)
		(pin "Y39"
		)
		(pin "Z04"
		)
		(pin "Z05"
		)
		(pin "Z08"
		)
		(pin "Z09"
		)
		(pin "Z12"
		)
		(pin "Z13"
		)
		(pin "Z16"
		)
		(pin "Z17"
		)
		(pin "Z24"
		)
		(pin "Z25"
		)
		(pin "Z28"
		)
		(pin "Z29"
		)
		(pin "Z32"
		)
		(pin "Z33"
		)
		(pin "Z36"
		)
		(pin "Z37"
		)
		(pin "A01"
		)
		(pin "A04"
		)
		(pin "A05"
		)
		(pin "A08"
		)
		(pin "A09"
		)
		(pin "A12"
		)
		(pin "A13"
		)
		(pin "A16"
		)
		(pin "A17"
		)
		(pin "A20"
		)
		(pin "A21"
		)
		(pin "A24"
		)
		(pin "A25"
		)
		(pin "A28"
		)
		(pin "A29"
		)
		(pin "A32"
		)
		(pin "A33"
		)
		(pin "A36"
		)
		(pin "A37"
		)
		(pin "A40"
		)
		(pin "B02"
		)
		(pin "B03"
		)
		(pin "B06"
		)
		(pin "B07"
		)
		(pin "B10"
		)
		(pin "B11"
		)
		(pin "B14"
		)
		(pin "B15"
		)
		(pin "B18"
		)
		(pin "B19"
		)
		(pin "B22"
		)
		(pin "B23"
		)
		(pin "B26"
		)
		(pin "B27"
		)
		(pin "B30"
		)
		(pin "B31"
		)
		(pin "B34"
		)
		(pin "B35"
		)
		(pin "B38"
		)
		(pin "B39"
		)
		(pin "B40"
		)
		(pin "C01"
		)
		(pin "C04"
		)
		(pin "C05"
		)
		(pin "C08"
		)
		(pin "C09"
		)
		(pin "C12"
		)
		(pin "C13"
		)
		(pin "C16"
		)
		(pin "C17"
		)
		(pin "C20"
		)
		(pin "C21"
		)
		(pin "C24"
		)
		(pin "C25"
		)
		(pin "C28"
		)
		(pin "C29"
		)
		(pin "C32"
		)
		(pin "C33"
		)
		(pin "C35"
		)
		(pin "C36"
		)
		(pin "C37"
		)
		(pin "C38"
		)
		(pin "C39"
		)
		(pin "C40"
		)
		(pin "D02"
		)
		(pin "D03"
		)
		(pin "D06"
		)
		(pin "D07"
		)
		(pin "D10"
		)
		(pin "D13"
		)
		(pin "D16"
		)
		(pin "D19"
		)
		(pin "D22"
		)
		(pin "D25"
		)
		(pin "D28"
		)
		(pin "D32"
		)
		(pin "D36"
		)
		(pin "D37"
		)
		(pin "D38"
		)
		(pin "D39"
		)
		(pin "D40"
		)
		(pin "E01"
		)
		(pin "E04"
		)
		(pin "E05"
		)
		(pin "E08"
		)
		(pin "E11"
		)
		(pin "E14"
		)
		(pin "E17"
		)
		(pin "E20"
		)
		(pin "E23"
		)
		(pin "E26"
		)
		(pin "E29"
		)
		(pin "E32"
		)
		(pin "E35"
		)
		(pin "E38"
		)
		(pin "E39"
		)
		(pin "E40"
		)
		(pin "F02"
		)
		(pin "F03"
		)
		(pin "F06"
		)
		(pin "F09"
		)
		(pin "F12"
		)
		(pin "F15"
		)
		(pin "F18"
		)
		(pin "F21"
		)
		(pin "F24"
		)
		(pin "F27"
		)
		(pin "F30"
		)
		(pin "F33"
		)
		(pin "F36"
		)
		(pin "F39"
		)
		(pin "F40"
		)
		(pin "G01"
		)
		(pin "G04"
		)
		(pin "G05"
		)
		(pin "G08"
		)
		(pin "G11"
		)
		(pin "G14"
		)
		(pin "G17"
		)
		(pin "G20"
		)
		(pin "G23"
		)
		(pin "G26"
		)
		(pin "G29"
		)
		(pin "G32"
		)
		(pin "G35"
		)
		(pin "G38"
		)
		(pin "G39"
		)
		(pin "G40"
		)
		(pin "H01"
		)
		(pin "Z34"
		)
		(pin "Z35"
		)
		(pin "Z38"
		)
		(pin "Z39"
		)
		(pin "Z40"
		)
		(pin "C30"
		)
		(pin "H03"
		)
		(pin "H06"
		)
		(pin "H09"
		)
		(pin "H12"
		)
		(pin "H15"
		)
		(pin "H18"
		)
		(pin "H21"
		)
		(pin "H24"
		)
		(pin "H27"
		)
		(pin "H30"
		)
		(pin "H33"
		)
		(pin "H36"
		)
		(pin "H39"
		)
		(pin "H40"
		)
		(pin "J01"
		)
		(pin "J04"
		)
		(pin "J05"
		)
		(pin "J08"
		)
		(pin "J11"
		)
		(pin "J14"
		)
		(pin "J17"
		)
		(pin "J20"
		)
		(pin "J23"
		)
		(pin "J26"
		)
		(pin "J29"
		)
		(pin "J32"
		)
		(pin "J35"
		)
		(pin "J38"
		)
		(pin "J39"
		)
		(pin "J40"
		)
		(pin "K01"
		)
		(pin "K02"
		)
		(pin "K03"
		)
		(pin "K06"
		)
		(pin "K09"
		)
		(pin "K12"
		)
		(pin "K15"
		)
		(pin "K18"
		)
		(pin "K21"
		)
		(pin "K24"
		)
		(pin "K27"
		)
		(pin "K30"
		)
		(pin "K33"
		)
		(pin "K36"
		)
		(pin "K39"
		)
		(pin "K40"
		)
		(pin "L01"
		)
		(pin "L02"
		)
		(pin "L03"
		)
		(pin "L06"
		)
		(pin "L07"
		)
		(pin "L10"
		)
		(pin "L11"
		)
		(pin "L14"
		)
		(pin "L15"
		)
		(pin "L18"
		)
		(pin "L19"
		)
		(pin "L22"
		)
		(pin "L23"
		)
		(pin "L26"
		)
		(pin "L27"
		)
		(pin "L30"
		)
		(pin "L31"
		)
		(pin "L32"
		)
		(pin "L33"
		)
		(pin "L34"
		)
		(pin "L35"
		)
		(pin "L36"
		)
		(pin "L37"
		)
		(pin "L38"
		)
		(pin "L39"
		)
		(pin "L40"
		)
		(pin "M01"
		)
		(pin "M04"
		)
		(pin "M05"
		)
		(pin "M08"
		)
		(pin "M09"
		)
		(pin "M12"
		)
		(pin "M13"
		)
		(pin "M16"
		)
		(pin "M17"
		)
		(pin "M20"
		)
		(pin "M21"
		)
		(pin "M24"
		)
		(pin "M25"
		)
		(pin "M28"
		)
		(pin "M29"
		)
		(pin "M32"
		)
		(pin "M33"
		)
		(pin "M36"
		)
		(pin "M37"
		)
		(pin "M40"
		)
		(pin "Y01"
		)
		(pin "Y04"
		)
		(pin "Y05"
		)
		(pin "Y08"
		)
		(pin "Y09"
		)
		(pin "Y12"
		)
		(pin "Y13"
		)
		(pin "Y16"
		)
		(pin "Y17"
		)
		(pin "Y20"
		)
		(pin "Y21"
		)
		(pin "Y24"
		)
		(pin "Y25"
		)
		(pin "Y28"
		)
		(pin "Y29"
		)
		(pin "Y32"
		)
		(pin "Y33"
		)
		(pin "Y36"
		)
		(pin "Y37"
		)
		(pin "Y40"
		)
		(pin "Z02"
		)
		(pin "Z03"
		)
		(pin "Z06"
		)
		(pin "Z07"
		)
		(pin "Z10"
		)
		(pin "Z11"
		)
		(pin "Z14"
		)
		(pin "Z15"
		)
		(pin "Z18"
		)
		(pin "Z19"
		)
		(pin "Z22"
		)
		(pin "Z23"
		)
		(pin "Z26"
		)
		(pin "Z27"
		)
		(pin "Z30"
		)
		(pin "Z31"
		)
		(pin "C31"
		)
		(pin "C34"
		)
		(pin "D01"
		)
		(pin "D29"
		)
		(pin "D30"
		)
		(pin "D31"
		)
		(pin "D33"
		)
		(pin "D34"
		)
		(pin "D35"
		)
		(pin "F01"
		)
		(pin "H02"
		)
		(pin "Z01"
		)
		(pin "C10"
		)
		(pin "C11"
		)
		(pin "C14"
		)
		(pin "C15"
		)
		(pin "C18"
		)
		(pin "C19"
		)
		(pin "C22"
		)
		(pin "C23"
		)
		(pin "C26"
		)
		(pin "C27"
		)
		(pin "D08"
		)
		(pin "D09"
		)
		(pin "D11"
		)
		(pin "D12"
		)
		(pin "D14"
		)
		(pin "D15"
		)
		(pin "D17"
		)
		(pin "D18"
		)
		(pin "D20"
		)
		(pin "D21"
		)
		(pin "D23"
		)
		(pin "D24"
		)
		(pin "D26"
		)
		(pin "D27"
		)
		(pin "G06"
		)
		(pin "G07"
		)
		(pin "G09"
		)
		(pin "G10"
		)
		(pin "G12"
		)
		(pin "G13"
		)
		(pin "G15"
		)
		(pin "G16"
		)
		(pin "G18"
		)
		(pin "G19"
		)
		(pin "G21"
		)
		(pin "G22"
		)
		(pin "G24"
		)
		(pin "G25"
		)
		(pin "G27"
		)
		(pin "G28"
		)
		(pin "G30"
		)
		(pin "G31"
		)
		(pin "G33"
		)
		(pin "G34"
		)
		(pin "G36"
		)
		(pin "G37"
		)
		(pin "H07"
		)
		(pin "H08"
		)
		(pin "H10"
		)
		(pin "H11"
		)
		(pin "H13"
		)
		(pin "H14"
		)
		(pin "H16"
		)
		(pin "H17"
		)
		(pin "H19"
		)
		(pin "H20"
		)
		(pin "H22"
		)
		(pin "H23"
		)
		(pin "H25"
		)
		(pin "H26"
		)
		(pin "H28"
		)
		(pin "H29"
		)
		(pin "H31"
		)
		(pin "H32"
		)
		(pin "H34"
		)
		(pin "H35"
		)
		(pin "H37"
		)
		(pin "H38"
		)
		(pin "E02"
		)
		(pin "E03"
		)
		(pin "E06"
		)
		(pin "E07"
		)
		(pin "E09"
		)
		(pin "E10"
		)
		(pin "E12"
		)
		(pin "E13"
		)
		(pin "E15"
		)
		(pin "E16"
		)
		(pin "E18"
		)
		(pin "E19"
		)
		(pin "F04"
		)
		(pin "F05"
		)
		(pin "F07"
		)
		(pin "F08"
		)
		(pin "F10"
		)
		(pin "F11"
		)
		(pin "F13"
		)
		(pin "F14"
		)
		(pin "F16"
		)
		(pin "F17"
		)
		(pin "F19"
		)
		(pin "F20"
		)
		(pin "J06"
		)
		(pin "J07"
		)
		(pin "J09"
		)
		(pin "J10"
		)
		(pin "J12"
		)
		(pin "J13"
		)
		(pin "J15"
		)
		(pin "J16"
		)
		(pin "J18"
		)
		(pin "J19"
		)
		(pin "J21"
		)
		(pin "J22"
		)
		(pin "K07"
		)
		(pin "K08"
		)
		(pin "K10"
		)
		(pin "K11"
		)
		(pin "K13"
		)
		(pin "K14"
		)
		(pin "K16"
		)
		(pin "K17"
		)
		(pin "K19"
		)
		(pin "K20"
		)
		(pin "K22"
		)
		(pin "K23"
		)
		(pin "E21"
		)
		(pin "E22"
		)
		(pin "E24"
		)
		(pin "E25"
		)
		(pin "E27"
		)
		(pin "E28"
		)
		(pin "E30"
		)
		(pin "E31"
		)
		(pin "E33"
		)
		(pin "E34"
		)
		(pin "E36"
		)
		(pin "E37"
		)
		(pin "F22"
		)
		(pin "F23"
		)
		(pin "F25"
		)
		(pin "F26"
		)
		(pin "F28"
		)
		(pin "F29"
		)
		(pin "F31"
		)
		(pin "F32"
		)
		(pin "F34"
		)
		(pin "F35"
		)
		(pin "F37"
		)
		(pin "F38"
		)
		(pin "J24"
		)
		(pin "J25"
		)
		(pin "J27"
		)
		(pin "J28"
		)
		(pin "J30"
		)
		(pin "J31"
		)
		(pin "J33"
		)
		(pin "J34"
		)
		(pin "J36"
		)
		(pin "J37"
		)
		(pin "K25"
		)
		(pin "K26"
		)
		(pin "K28"
		)
		(pin "K29"
		)
		(pin "K31"
		)
		(pin "K32"
		)
		(pin "K34"
		)
		(pin "K35"
		)
		(pin "K37"
		)
		(pin "K38"
		)
		(pin "B01"
		)
		(pin "G02"
		)
		(pin "G03"
		)
		(pin "H04"
		)
		(pin "H05"
		)
		(pin "J02"
		)
		(pin "J03"
		)
		(pin "K04"
		)
		(pin "K05"
		)
		(pin "B20"
		)
		(pin "B21"
		)
		(pin "D04"
		)
		(pin "D05"
		)
		(pin "L04"
		)
		(pin "L05"
		)
		(pin "L08"
		)
		(pin "L09"
		)
		(pin "L12"
		)
		(pin "L13"
		)
		(pin "L16"
		)
		(pin "L17"
		)
		(pin "L20"
		)
		(pin "L21"
		)
		(pin "L24"
		)
		(pin "L25"
		)
		(pin "L28"
		)
		(pin "L29"
		)
		(pin "Z20"
		)
		(pin "Z21"
		)
		(instances
			(project "k410t-devboard"
				(path ""
					(reference "J18")
					(unit 8)
				)
			)
		)
	)
	(symbol
		(lib_id "antmicroB2BConnectors:ASP-184329-01_CUSTOM_mounting_holes")
		(at 279.4 107.95 0)
		(unit 6)
		(exclude_from_sim no)
		(in_bom yes)
		(on_board yes)
		(dnp no)
		(fields_autoplaced yes)
		(property "Reference" "J18"
			(at 266.7 93.98 0)
			(effects
				(font
					(size 1.27 1.27)
					(thickness 0.15)
				)
			)
		)
		(property "Value" "ASP-184329-01_mounting_holes"
			(at 266.7 97.155 0)
			(effects
				(font
					(size 1.27 1.27)
					(thickness 0.15)
				)
				(hide yes)
			)
		)
		(property "Footprint" "antmicro-footprints:ASP-184329-01_mounting_holes"
			(at 325.12 119.38 0)
			(effects
				(font
					(size 1.27 1.27)
					(thickness 0.15)
				)
				(justify left bottom)
				(hide yes)
			)
		)
		(property "Datasheet" "https://www.mouser.com/datasheet/2/527/asp_184329_01_mkt-2854128.pdf"
			(at 325.12 121.92 0)
			(effects
				(font
					(size 1.27 1.27)
					(thickness 0.15)
				)
				(justify left bottom)
				(hide yes)
			)
		)
		(property "Description" ""
			(at 279.4 107.95 0)
			(effects
				(font
					(size 1.27 1.27)
				)
			)
		)
		(property "Manufacturer" "Samtec"
			(at 325.12 124.46 0)
			(effects
				(font
					(size 1.27 1.27)
					(thickness 0.15)
				)
				(justify left bottom)
				(hide yes)
			)
		)
		(property "MPN" "ASP-184329-01"
			(at 266.7 96.52 0)
			(effects
				(font
					(size 1.27 1.27)
					(thickness 0.15)
				)
			)
		)
		(property "Author" "Antmicro"
			(at 325.12 129.54 0)
			(effects
				(font
					(size 1.27 1.27)
					(thickness 0.15)
				)
				(justify left bottom)
				(hide yes)
			)
		)
		(property "License" "Apache-2.0"
			(at 325.12 132.08 0)
			(effects
				(font
					(size 1.27 1.27)
					(thickness 0.15)
				)
				(justify left bottom)
				(hide yes)
			)
		)
		(pin "B01"
		)
		(pin "G02"
		)
		(pin "G03"
		)
		(pin "H04"
		)
		(pin "H05"
		)
		(pin "J02"
		)
		(pin "J03"
		)
		(pin "K04"
		)
		(pin "K05"
		)
		(pin "Z34"
		)
		(pin "Z35"
		)
		(pin "Z38"
		)
		(pin "Z39"
		)
		(pin "Z40"
		)
		(pin "C30"
		)
		(pin "H03"
		)
		(pin "H06"
		)
		(pin "H09"
		)
		(pin "H12"
		)
		(pin "H15"
		)
		(pin "H18"
		)
		(pin "H21"
		)
		(pin "H24"
		)
		(pin "H27"
		)
		(pin "H30"
		)
		(pin "H33"
		)
		(pin "H36"
		)
		(pin "H39"
		)
		(pin "H40"
		)
		(pin "J01"
		)
		(pin "J04"
		)
		(pin "J05"
		)
		(pin "J08"
		)
		(pin "J11"
		)
		(pin "J14"
		)
		(pin "J17"
		)
		(pin "J20"
		)
		(pin "J23"
		)
		(pin "J26"
		)
		(pin "J29"
		)
		(pin "J32"
		)
		(pin "J35"
		)
		(pin "J38"
		)
		(pin "J39"
		)
		(pin "J40"
		)
		(pin "K01"
		)
		(pin "K02"
		)
		(pin "K03"
		)
		(pin "K06"
		)
		(pin "K09"
		)
		(pin "K12"
		)
		(pin "K15"
		)
		(pin "K18"
		)
		(pin "K21"
		)
		(pin "K24"
		)
		(pin "K27"
		)
		(pin "K30"
		)
		(pin "K33"
		)
		(pin "K36"
		)
		(pin "K39"
		)
		(pin "K40"
		)
		(pin "L01"
		)
		(pin "L02"
		)
		(pin "L03"
		)
		(pin "L06"
		)
		(pin "L07"
		)
		(pin "L10"
		)
		(pin "L11"
		)
		(pin "L14"
		)
		(pin "L15"
		)
		(pin "L18"
		)
		(pin "L19"
		)
		(pin "L22"
		)
		(pin "L23"
		)
		(pin "L26"
		)
		(pin "L27"
		)
		(pin "A01"
		)
		(pin "A04"
		)
		(pin "A05"
		)
		(pin "A08"
		)
		(pin "A09"
		)
		(pin "A12"
		)
		(pin "A13"
		)
		(pin "A16"
		)
		(pin "A17"
		)
		(pin "A20"
		)
		(pin "A21"
		)
		(pin "A24"
		)
		(pin "A25"
		)
		(pin "A28"
		)
		(pin "A29"
		)
		(pin "A32"
		)
		(pin "A33"
		)
		(pin "A36"
		)
		(pin "A37"
		)
		(pin "A40"
		)
		(pin "B02"
		)
		(pin "B03"
		)
		(pin "B06"
		)
		(pin "B07"
		)
		(pin "B10"
		)
		(pin "B11"
		)
		(pin "B14"
		)
		(pin "B15"
		)
		(pin "B18"
		)
		(pin "B19"
		)
		(pin "B22"
		)
		(pin "B23"
		)
		(pin "B26"
		)
		(pin "B27"
		)
		(pin "B30"
		)
		(pin "B31"
		)
		(pin "B34"
		)
		(pin "B35"
		)
		(pin "B38"
		)
		(pin "B39"
		)
		(pin "B40"
		)
		(pin "C01"
		)
		(pin "C04"
		)
		(pin "C05"
		)
		(pin "C08"
		)
		(pin "C09"
		)
		(pin "C12"
		)
		(pin "C13"
		)
		(pin "C16"
		)
		(pin "C17"
		)
		(pin "C20"
		)
		(pin "C21"
		)
		(pin "C24"
		)
		(pin "C25"
		)
		(pin "C28"
		)
		(pin "C29"
		)
		(pin "C32"
		)
		(pin "C33"
		)
		(pin "C35"
		)
		(pin "C36"
		)
		(pin "C37"
		)
		(pin "C38"
		)
		(pin "C39"
		)
		(pin "C40"
		)
		(pin "D02"
		)
		(pin "D03"
		)
		(pin "D06"
		)
		(pin "D07"
		)
		(pin "D10"
		)
		(pin "D13"
		)
		(pin "D16"
		)
		(pin "D19"
		)
		(pin "D22"
		)
		(pin "D25"
		)
		(pin "D28"
		)
		(pin "D32"
		)
		(pin "D36"
		)
		(pin "D37"
		)
		(pin "D38"
		)
		(pin "D39"
		)
		(pin "D40"
		)
		(pin "E01"
		)
		(pin "E04"
		)
		(pin "E05"
		)
		(pin "E08"
		)
		(pin "E11"
		)
		(pin "E14"
		)
		(pin "E17"
		)
		(pin "E20"
		)
		(pin "E23"
		)
		(pin "E26"
		)
		(pin "E29"
		)
		(pin "E32"
		)
		(pin "E35"
		)
		(pin "E38"
		)
		(pin "E39"
		)
		(pin "E40"
		)
		(pin "F02"
		)
		(pin "F03"
		)
		(pin "F06"
		)
		(pin "F09"
		)
		(pin "F12"
		)
		(pin "F15"
		)
		(pin "F18"
		)
		(pin "F21"
		)
		(pin "F24"
		)
		(pin "F27"
		)
		(pin "F30"
		)
		(pin "F33"
		)
		(pin "F36"
		)
		(pin "F39"
		)
		(pin "F40"
		)
		(pin "G01"
		)
		(pin "G04"
		)
		(pin "G05"
		)
		(pin "G08"
		)
		(pin "G11"
		)
		(pin "G14"
		)
		(pin "G17"
		)
		(pin "G20"
		)
		(pin "G23"
		)
		(pin "G26"
		)
		(pin "G29"
		)
		(pin "G32"
		)
		(pin "G35"
		)
		(pin "G38"
		)
		(pin "G39"
		)
		(pin "G40"
		)
		(pin "H01"
		)
		(pin "L30"
		)
		(pin "L31"
		)
		(pin "L32"
		)
		(pin "L33"
		)
		(pin "L34"
		)
		(pin "L35"
		)
		(pin "L36"
		)
		(pin "L37"
		)
		(pin "L38"
		)
		(pin "L39"
		)
		(pin "L40"
		)
		(pin "M01"
		)
		(pin "M04"
		)
		(pin "M05"
		)
		(pin "M08"
		)
		(pin "M09"
		)
		(pin "M12"
		)
		(pin "M13"
		)
		(pin "M16"
		)
		(pin "M17"
		)
		(pin "M20"
		)
		(pin "M21"
		)
		(pin "M24"
		)
		(pin "M25"
		)
		(pin "M28"
		)
		(pin "M29"
		)
		(pin "M32"
		)
		(pin "M33"
		)
		(pin "M36"
		)
		(pin "M37"
		)
		(pin "M40"
		)
		(pin "Y01"
		)
		(pin "Y04"
		)
		(pin "Y05"
		)
		(pin "Y08"
		)
		(pin "Y09"
		)
		(pin "Y12"
		)
		(pin "Y13"
		)
		(pin "Y16"
		)
		(pin "Y17"
		)
		(pin "Y20"
		)
		(pin "Y21"
		)
		(pin "Y24"
		)
		(pin "Y25"
		)
		(pin "Y28"
		)
		(pin "Y29"
		)
		(pin "Y32"
		)
		(pin "Y33"
		)
		(pin "Y36"
		)
		(pin "Y37"
		)
		(pin "Y40"
		)
		(pin "Z02"
		)
		(pin "Z03"
		)
		(pin "Z06"
		)
		(pin "Z07"
		)
		(pin "Z10"
		)
		(pin "Z11"
		)
		(pin "Z14"
		)
		(pin "Z15"
		)
		(pin "Z18"
		)
		(pin "Z19"
		)
		(pin "Z22"
		)
		(pin "Z23"
		)
		(pin "Z26"
		)
		(pin "Z27"
		)
		(pin "Z30"
		)
		(pin "Z31"
		)
		(pin "M19"
		)
		(pin "M22"
		)
		(pin "M23"
		)
		(pin "M26"
		)
		(pin "M27"
		)
		(pin "M30"
		)
		(pin "M31"
		)
		(pin "M34"
		)
		(pin "M35"
		)
		(pin "M38"
		)
		(pin "C31"
		)
		(pin "C34"
		)
		(pin "D01"
		)
		(pin "D29"
		)
		(pin "D30"
		)
		(pin "D31"
		)
		(pin "D33"
		)
		(pin "D34"
		)
		(pin "D35"
		)
		(pin "F01"
		)
		(pin "H02"
		)
		(pin "Z01"
		)
		(pin "C10"
		)
		(pin "C11"
		)
		(pin "C14"
		)
		(pin "C15"
		)
		(pin "C18"
		)
		(pin "C19"
		)
		(pin "C22"
		)
		(pin "C23"
		)
		(pin "C26"
		)
		(pin "C27"
		)
		(pin "D08"
		)
		(pin "D09"
		)
		(pin "D11"
		)
		(pin "D12"
		)
		(pin "D14"
		)
		(pin "D15"
		)
		(pin "D17"
		)
		(pin "D18"
		)
		(pin "D20"
		)
		(pin "D21"
		)
		(pin "D23"
		)
		(pin "D24"
		)
		(pin "D26"
		)
		(pin "D27"
		)
		(pin "G06"
		)
		(pin "G07"
		)
		(pin "G09"
		)
		(pin "G10"
		)
		(pin "G12"
		)
		(pin "G13"
		)
		(pin "G15"
		)
		(pin "G16"
		)
		(pin "G18"
		)
		(pin "G19"
		)
		(pin "G21"
		)
		(pin "G22"
		)
		(pin "G24"
		)
		(pin "G25"
		)
		(pin "G27"
		)
		(pin "G28"
		)
		(pin "G30"
		)
		(pin "G31"
		)
		(pin "G33"
		)
		(pin "G34"
		)
		(pin "G36"
		)
		(pin "G37"
		)
		(pin "H07"
		)
		(pin "H08"
		)
		(pin "H10"
		)
		(pin "H11"
		)
		(pin "H13"
		)
		(pin "H14"
		)
		(pin "H16"
		)
		(pin "H17"
		)
		(pin "H19"
		)
		(pin "H20"
		)
		(pin "H22"
		)
		(pin "H23"
		)
		(pin "H25"
		)
		(pin "H26"
		)
		(pin "H28"
		)
		(pin "H29"
		)
		(pin "H31"
		)
		(pin "H32"
		)
		(pin "H34"
		)
		(pin "H35"
		)
		(pin "H37"
		)
		(pin "H38"
		)
		(pin "E02"
		)
		(pin "E03"
		)
		(pin "E06"
		)
		(pin "E07"
		)
		(pin "E09"
		)
		(pin "E10"
		)
		(pin "E12"
		)
		(pin "E13"
		)
		(pin "E15"
		)
		(pin "E16"
		)
		(pin "E18"
		)
		(pin "E19"
		)
		(pin "F04"
		)
		(pin "F05"
		)
		(pin "F07"
		)
		(pin "F08"
		)
		(pin "F10"
		)
		(pin "F11"
		)
		(pin "F13"
		)
		(pin "F14"
		)
		(pin "F16"
		)
		(pin "F17"
		)
		(pin "F19"
		)
		(pin "F20"
		)
		(pin "J06"
		)
		(pin "J07"
		)
		(pin "J09"
		)
		(pin "J10"
		)
		(pin "J12"
		)
		(pin "J13"
		)
		(pin "J15"
		)
		(pin "J16"
		)
		(pin "J18"
		)
		(pin "J19"
		)
		(pin "J21"
		)
		(pin "J22"
		)
		(pin "K07"
		)
		(pin "K08"
		)
		(pin "K10"
		)
		(pin "K11"
		)
		(pin "K13"
		)
		(pin "K14"
		)
		(pin "K16"
		)
		(pin "K17"
		)
		(pin "K19"
		)
		(pin "K20"
		)
		(pin "K22"
		)
		(pin "K23"
		)
		(pin "E21"
		)
		(pin "E22"
		)
		(pin "E24"
		)
		(pin "E25"
		)
		(pin "E27"
		)
		(pin "E28"
		)
		(pin "E30"
		)
		(pin "E31"
		)
		(pin "E33"
		)
		(pin "E34"
		)
		(pin "E36"
		)
		(pin "E37"
		)
		(pin "F22"
		)
		(pin "F23"
		)
		(pin "F25"
		)
		(pin "F26"
		)
		(pin "F28"
		)
		(pin "F29"
		)
		(pin "F31"
		)
		(pin "F32"
		)
		(pin "F34"
		)
		(pin "F35"
		)
		(pin "F37"
		)
		(pin "F38"
		)
		(pin "J24"
		)
		(pin "J25"
		)
		(pin "J27"
		)
		(pin "J28"
		)
		(pin "J30"
		)
		(pin "J31"
		)
		(pin "J33"
		)
		(pin "J34"
		)
		(pin "J36"
		)
		(pin "J37"
		)
		(pin "K25"
		)
		(pin "K26"
		)
		(pin "K28"
		)
		(pin "K29"
		)
		(pin "K31"
		)
		(pin "K32"
		)
		(pin "K34"
		)
		(pin "K35"
		)
		(pin "K37"
		)
		(pin "K38"
		)
		(pin "B20"
		)
		(pin "B21"
		)
		(pin "D04"
		)
		(pin "D05"
		)
		(pin "L04"
		)
		(pin "L05"
		)
		(pin "L08"
		)
		(pin "L09"
		)
		(pin "L12"
		)
		(pin "L13"
		)
		(pin "L16"
		)
		(pin "L17"
		)
		(pin "L20"
		)
		(pin "L21"
		)
		(pin "L24"
		)
		(pin "L25"
		)
		(pin "L28"
		)
		(pin "L29"
		)
		(pin "Z20"
		)
		(pin "Z21"
		)
		(pin "A02"
		)
		(pin "A03"
		)
		(pin "A06"
		)
		(pin "A07"
		)
		(pin "A10"
		)
		(pin "A11"
		)
		(pin "A14"
		)
		(pin "A15"
		)
		(pin "A18"
		)
		(pin "A19"
		)
		(pin "A22"
		)
		(pin "A23"
		)
		(pin "A26"
		)
		(pin "A27"
		)
		(pin "A30"
		)
		(pin "A31"
		)
		(pin "A34"
		)
		(pin "A35"
		)
		(pin "A38"
		)
		(pin "A39"
		)
		(pin "B04"
		)
		(pin "B05"
		)
		(pin "B08"
		)
		(pin "B09"
		)
		(pin "B12"
		)
		(pin "B13"
		)
		(pin "B16"
		)
		(pin "B17"
		)
		(pin "B24"
		)
		(pin "B25"
		)
		(pin "B28"
		)
		(pin "B29"
		)
		(pin "B32"
		)
		(pin "B33"
		)
		(pin "B36"
		)
		(pin "B37"
		)
		(pin "C02"
		)
		(pin "C03"
		)
		(pin "C06"
		)
		(pin "C07"
		)
		(pin "M02"
		)
		(pin "M03"
		)
		(pin "M06"
		)
		(pin "M07"
		)
		(pin "M10"
		)
		(pin "M11"
		)
		(pin "M14"
		)
		(pin "M15"
		)
		(pin "M18"
		)
		(pin "M39"
		)
		(pin "Y02"
		)
		(pin "Y03"
		)
		(pin "Y06"
		)
		(pin "Y07"
		)
		(pin "Y10"
		)
		(pin "Y11"
		)
		(pin "Y14"
		)
		(pin "Y15"
		)
		(pin "Y18"
		)
		(pin "Y19"
		)
		(pin "Y22"
		)
		(pin "Y23"
		)
		(pin "Y26"
		)
		(pin "Y27"
		)
		(pin "Y30"
		)
		(pin "Y31"
		)
		(pin "Y34"
		)
		(pin "Y35"
		)
		(pin "Y38"
		)
		(pin "Y39"
		)
		(pin "Z04"
		)
		(pin "Z05"
		)
		(pin "Z08"
		)
		(pin "Z09"
		)
		(pin "Z12"
		)
		(pin "Z13"
		)
		(pin "Z16"
		)
		(pin "Z17"
		)
		(pin "Z24"
		)
		(pin "Z25"
		)
		(pin "Z28"
		)
		(pin "Z29"
		)
		(pin "Z32"
		)
		(pin "Z33"
		)
		(pin "Z36"
		)
		(pin "Z37"
		)
		(instances
			(project "k410t-devboard"
				(path ""
					(reference "J18")
					(unit 6)
				)
			)
		)
	)
	(symbol
		(lib_id "antmicropower:GND")
		(at 38.1 57.15 0)
		(unit 1)
		(exclude_from_sim no)
		(in_bom yes)
		(on_board yes)
		(dnp no)
		(property "Reference" "#PWR0350"
			(at 38.1 63.5 0)
			(effects
				(font
					(size 1.27 1.27)
				)
				(hide yes)
			)
		)
		(property "Value" "GND"
			(at 38.1 60.96 0)
			(effects
				(font
					(size 1.27 1.27)
				)
			)
		)
		(property "Footprint" ""
			(at 46.99 64.77 0)
			(effects
				(font
					(size 1.27 1.27)
					(thickness 0.15)
				)
				(justify left bottom)
				(hide yes)
			)
		)
		(property "Datasheet" ""
			(at 46.99 69.85 0)
			(effects
				(font
					(size 1.27 1.27)
					(thickness 0.15)
				)
				(justify left bottom)
				(hide yes)
			)
		)
		(property "Description" ""
			(at 38.1 57.15 0)
			(effects
				(font
					(size 1.27 1.27)
				)
			)
		)
		(property "Author" "Antmicro"
			(at 46.99 64.77 0)
			(effects
				(font
					(size 1.27 1.27)
					(thickness 0.15)
				)
				(justify left bottom)
				(hide yes)
			)
		)
		(property "License" "Apache-2.0"
			(at 46.99 67.31 0)
			(effects
				(font
					(size 1.27 1.27)
					(thickness 0.15)
				)
				(justify left bottom)
				(hide yes)
			)
		)
		(pin "1"
		)
		(instances
			(project "k410t-devboard"
				(path ""
					(reference "#PWR0350")
					(unit 1)
				)
			)
		)
	)
	(symbol
		(lib_id "antmicroCapacitors0402:C_100n_0402")
		(at 353.06 204.47 180)
		(unit 1)
		(exclude_from_sim no)
		(in_bom yes)
		(on_board yes)
		(dnp no)
		(property "Reference" "C309"
			(at 355.6 203.2 0)
			(effects
				(font
					(size 1.27 1.27)
				)
			)
		)
		(property "Value" "C_100n_0402"
			(at 332.74 194.31 0)
			(effects
				(font
					(size 1.27 1.27)
					(thickness 0.15)
				)
				(justify left bottom)
				(hide yes)
			)
		)
		(property "Footprint" "antmicro-footprints:C_0402_1005Metric"
			(at 332.74 191.77 0)
			(effects
				(font
					(size 1.27 1.27)
					(thickness 0.15)
				)
				(justify left bottom)
				(hide yes)
			)
		)
		(property "Datasheet" "https://www.murata.com/products/productdetail?partno=GRM155R61H104KE14%23"
			(at 332.74 189.23 0)
			(effects
				(font
					(size 1.27 1.27)
					(thickness 0.15)
				)
				(justify left bottom)
				(hide yes)
			)
		)
		(property "Description" ""
			(at 353.06 204.47 0)
			(effects
				(font
					(size 1.27 1.27)
				)
			)
		)
		(property "Manufacturer" "Murata"
			(at 332.74 184.15 0)
			(effects
				(font
					(size 1.27 1.27)
					(thickness 0.15)
				)
				(justify left bottom)
				(hide yes)
			)
		)
		(property "MPN" "GRM155R61H104KE14D"
			(at 332.74 186.69 0)
			(effects
				(font
					(size 1.27 1.27)
					(thickness 0.15)
				)
				(justify left bottom)
				(hide yes)
			)
		)
		(property "Val" "100n"
			(at 346.075 203.2 0)
			(effects
				(font
					(size 1.27 1.27)
					(thickness 0.15)
				)
			)
		)
		(property "License" "Apache-2.0"
			(at 332.74 181.61 0)
			(effects
				(font
					(size 1.27 1.27)
					(thickness 0.15)
				)
				(justify left bottom)
				(hide yes)
			)
		)
		(property "Author" "Antmicro"
			(at 332.74 179.07 0)
			(effects
				(font
					(size 1.27 1.27)
					(thickness 0.15)
				)
				(justify left bottom)
				(hide yes)
			)
		)
		(property "Voltage" "50V"
			(at 332.74 176.53 0)
			(effects
				(font
					(size 1.27 1.27)
				)
				(justify left bottom)
				(hide yes)
			)
		)
		(property "Dielectric" "X5R"
			(at 332.74 173.99 0)
			(effects
				(font
					(size 1.27 1.27)
				)
				(justify left bottom)
				(hide yes)
			)
		)
		(pin "1"
		)
		(pin "2"
		)
		(instances
			(project "k410t-devboard"
				(path ""
					(reference "C309")
					(unit 1)
				)
			)
		)
	)
	(symbol
		(lib_id "antmicroResistors0402:R_4k7_0402")
		(at 203.2 52.07 90)
		(unit 1)
		(exclude_from_sim no)
		(in_bom yes)
		(on_board yes)
		(dnp no)
		(property "Reference" "R268"
			(at 204.47 48.26 90)
			(effects
				(font
					(size 1.27 1.27)
				)
				(justify right)
			)
		)
		(property "Value" "R_4k7_0402"
			(at 215.9 31.75 0)
			(effects
				(font
					(size 1.27 1.27)
					(thickness 0.15)
				)
				(justify left bottom)
				(hide yes)
			)
		)
		(property "Footprint" "antmicro-footprints:R_0402_1005Metric"
			(at 218.44 31.75 0)
			(effects
				(font
					(size 1.27 1.27)
					(thickness 0.15)
				)
				(justify left bottom)
				(hide yes)
			)
		)
		(property "Datasheet" "https://www.bourns.com/docs/product-datasheets/cr.pdf"
			(at 220.98 31.75 0)
			(effects
				(font
					(size 1.27 1.27)
					(thickness 0.15)
				)
				(justify left bottom)
				(hide yes)
			)
		)
		(property "Description" ""
			(at 203.2 52.07 0)
			(effects
				(font
					(size 1.27 1.27)
				)
			)
		)
		(property "Manufacturer" "Bourns"
			(at 226.06 31.75 0)
			(effects
				(font
					(size 1.27 1.27)
					(thickness 0.15)
				)
				(justify left bottom)
				(hide yes)
			)
		)
		(property "MPN" "CR0402-FX-4701GLF"
			(at 223.52 31.75 0)
			(effects
				(font
					(size 1.27 1.27)
					(thickness 0.15)
				)
				(justify left bottom)
				(hide yes)
			)
		)
		(property "Val" "4k7"
			(at 204.47 50.8 90)
			(effects
				(font
					(size 1.27 1.27)
					(thickness 0.15)
				)
				(justify right)
			)
		)
		(property "License" "Apache-2.0"
			(at 228.6 31.75 0)
			(effects
				(font
					(size 1.27 1.27)
					(thickness 0.15)
				)
				(justify left bottom)
				(hide yes)
			)
		)
		(property "Author" "Antmicro"
			(at 231.14 31.75 0)
			(effects
				(font
					(size 1.27 1.27)
					(thickness 0.15)
				)
				(justify left bottom)
				(hide yes)
			)
		)
		(property "Tolerance" "1%"
			(at 213.36 31.75 0)
			(effects
				(font
					(size 1.27 1.27)
				)
				(justify left bottom)
				(hide yes)
			)
		)
		(pin "1"
		)
		(pin "2"
		)
		(instances
			(project "k410t-devboard"
				(path ""
					(reference "R268")
					(unit 1)
				)
			)
		)
	)
	(symbol
		(lib_id "antmicroCapacitors0402:C_100n_0402")
		(at 353.06 214.63 180)
		(unit 1)
		(exclude_from_sim no)
		(in_bom yes)
		(on_board yes)
		(dnp no)
		(property "Reference" "C311"
			(at 355.6 213.36 0)
			(effects
				(font
					(size 1.27 1.27)
				)
			)
		)
		(property "Value" "C_100n_0402"
			(at 332.74 204.47 0)
			(effects
				(font
					(size 1.27 1.27)
					(thickness 0.15)
				)
				(justify left bottom)
				(hide yes)
			)
		)
		(property "Footprint" "antmicro-footprints:C_0402_1005Metric"
			(at 332.74 201.93 0)
			(effects
				(font
					(size 1.27 1.27)
					(thickness 0.15)
				)
				(justify left bottom)
				(hide yes)
			)
		)
		(property "Datasheet" "https://www.murata.com/products/productdetail?partno=GRM155R61H104KE14%23"
			(at 332.74 199.39 0)
			(effects
				(font
					(size 1.27 1.27)
					(thickness 0.15)
				)
				(justify left bottom)
				(hide yes)
			)
		)
		(property "Description" ""
			(at 353.06 214.63 0)
			(effects
				(font
					(size 1.27 1.27)
				)
			)
		)
		(property "Manufacturer" "Murata"
			(at 332.74 194.31 0)
			(effects
				(font
					(size 1.27 1.27)
					(thickness 0.15)
				)
				(justify left bottom)
				(hide yes)
			)
		)
		(property "MPN" "GRM155R61H104KE14D"
			(at 332.74 196.85 0)
			(effects
				(font
					(size 1.27 1.27)
					(thickness 0.15)
				)
				(justify left bottom)
				(hide yes)
			)
		)
		(property "Val" "100n"
			(at 346.075 213.36 0)
			(effects
				(font
					(size 1.27 1.27)
					(thickness 0.15)
				)
			)
		)
		(property "License" "Apache-2.0"
			(at 332.74 191.77 0)
			(effects
				(font
					(size 1.27 1.27)
					(thickness 0.15)
				)
				(justify left bottom)
				(hide yes)
			)
		)
		(property "Author" "Antmicro"
			(at 332.74 189.23 0)
			(effects
				(font
					(size 1.27 1.27)
					(thickness 0.15)
				)
				(justify left bottom)
				(hide yes)
			)
		)
		(property "Voltage" "50V"
			(at 332.74 186.69 0)
			(effects
				(font
					(size 1.27 1.27)
				)
				(justify left bottom)
				(hide yes)
			)
		)
		(property "Dielectric" "X5R"
			(at 332.74 184.15 0)
			(effects
				(font
					(size 1.27 1.27)
				)
				(justify left bottom)
				(hide yes)
			)
		)
		(pin "1"
		)
		(pin "2"
		)
		(instances
			(project "k410t-devboard"
				(path ""
					(reference "C311")
					(unit 1)
				)
			)
		)
	)
	(symbol
		(lib_id "antmicroCapacitors0402:C_100n_0402")
		(at 353.06 199.39 180)
		(unit 1)
		(exclude_from_sim no)
		(in_bom yes)
		(on_board yes)
		(dnp no)
		(property "Reference" "C308"
			(at 355.6 198.12 0)
			(effects
				(font
					(size 1.27 1.27)
				)
			)
		)
		(property "Value" "C_100n_0402"
			(at 332.74 189.23 0)
			(effects
				(font
					(size 1.27 1.27)
					(thickness 0.15)
				)
				(justify left bottom)
				(hide yes)
			)
		)
		(property "Footprint" "antmicro-footprints:C_0402_1005Metric"
			(at 332.74 186.69 0)
			(effects
				(font
					(size 1.27 1.27)
					(thickness 0.15)
				)
				(justify left bottom)
				(hide yes)
			)
		)
		(property "Datasheet" "https://www.murata.com/products/productdetail?partno=GRM155R61H104KE14%23"
			(at 332.74 184.15 0)
			(effects
				(font
					(size 1.27 1.27)
					(thickness 0.15)
				)
				(justify left bottom)
				(hide yes)
			)
		)
		(property "Description" ""
			(at 353.06 199.39 0)
			(effects
				(font
					(size 1.27 1.27)
				)
			)
		)
		(property "Manufacturer" "Murata"
			(at 332.74 179.07 0)
			(effects
				(font
					(size 1.27 1.27)
					(thickness 0.15)
				)
				(justify left bottom)
				(hide yes)
			)
		)
		(property "MPN" "GRM155R61H104KE14D"
			(at 332.74 181.61 0)
			(effects
				(font
					(size 1.27 1.27)
					(thickness 0.15)
				)
				(justify left bottom)
				(hide yes)
			)
		)
		(property "Val" "100n"
			(at 346.075 198.12 0)
			(effects
				(font
					(size 1.27 1.27)
					(thickness 0.15)
				)
			)
		)
		(property "License" "Apache-2.0"
			(at 332.74 176.53 0)
			(effects
				(font
					(size 1.27 1.27)
					(thickness 0.15)
				)
				(justify left bottom)
				(hide yes)
			)
		)
		(property "Author" "Antmicro"
			(at 332.74 173.99 0)
			(effects
				(font
					(size 1.27 1.27)
					(thickness 0.15)
				)
				(justify left bottom)
				(hide yes)
			)
		)
		(property "Voltage" "50V"
			(at 332.74 171.45 0)
			(effects
				(font
					(size 1.27 1.27)
				)
				(justify left bottom)
				(hide yes)
			)
		)
		(property "Dielectric" "X5R"
			(at 332.74 168.91 0)
			(effects
				(font
					(size 1.27 1.27)
				)
				(justify left bottom)
				(hide yes)
			)
		)
		(pin "1"
		)
		(pin "2"
		)
		(instances
			(project "k410t-devboard"
				(path ""
					(reference "C308")
					(unit 1)
				)
			)
		)
	)
	(symbol
		(lib_id "antmicroResistors0402:R_33R_0402")
		(at 349.25 57.15 0)
		(unit 1)
		(exclude_from_sim no)
		(in_bom yes)
		(on_board yes)
		(dnp no)
		(property "Reference" "R274"
			(at 356.87 55.88 0)
			(effects
				(font
					(size 1.27 1.27)
				)
			)
		)
		(property "Value" "R_33R_0402"
			(at 369.57 69.85 0)
			(effects
				(font
					(size 1.27 1.27)
					(thickness 0.15)
				)
				(justify left bottom)
				(hide yes)
			)
		)
		(property "Footprint" "antmicro-footprints:R_0402_1005Metric"
			(at 369.57 72.39 0)
			(effects
				(font
					(size 1.27 1.27)
					(thickness 0.15)
				)
				(justify left bottom)
				(hide yes)
			)
		)
		(property "Datasheet" "https://www.bourns.com/docs/product-datasheets/cr.pdf"
			(at 369.57 74.93 0)
			(effects
				(font
					(size 1.27 1.27)
					(thickness 0.15)
				)
				(justify left bottom)
				(hide yes)
			)
		)
		(property "Description" ""
			(at 349.25 57.15 0)
			(effects
				(font
					(size 1.27 1.27)
				)
			)
		)
		(property "Manufacturer" "Bourns"
			(at 369.57 80.01 0)
			(effects
				(font
					(size 1.27 1.27)
					(thickness 0.15)
				)
				(justify left bottom)
				(hide yes)
			)
		)
		(property "MPN" "CR0402-FX-33R0GLF"
			(at 369.57 77.47 0)
			(effects
				(font
					(size 1.27 1.27)
					(thickness 0.15)
				)
				(justify left bottom)
				(hide yes)
			)
		)
		(property "Val" "33R"
			(at 347.345 55.88 0)
			(effects
				(font
					(size 1.27 1.27)
					(thickness 0.15)
				)
			)
		)
		(property "License" "Apache-2.0"
			(at 369.57 82.55 0)
			(effects
				(font
					(size 1.27 1.27)
					(thickness 0.15)
				)
				(justify left bottom)
				(hide yes)
			)
		)
		(property "Author" "Antmicro"
			(at 369.57 85.09 0)
			(effects
				(font
					(size 1.27 1.27)
					(thickness 0.15)
				)
				(justify left bottom)
				(hide yes)
			)
		)
		(property "Tolerance" "1%"
			(at 369.57 67.31 0)
			(effects
				(font
					(size 1.27 1.27)
				)
				(justify left bottom)
				(hide yes)
			)
		)
		(pin "1"
		)
		(pin "2"
		)
		(instances
			(project "k410t-devboard"
				(path ""
					(reference "R274")
					(unit 1)
				)
			)
		)
	)
	(symbol
		(lib_id "antmicroCapacitors0402:C_100n_0402")
		(at 353.06 224.79 180)
		(unit 1)
		(exclude_from_sim no)
		(in_bom yes)
		(on_board yes)
		(dnp no)
		(property "Reference" "C313"
			(at 355.6 223.52 0)
			(effects
				(font
					(size 1.27 1.27)
				)
			)
		)
		(property "Value" "C_100n_0402"
			(at 332.74 214.63 0)
			(effects
				(font
					(size 1.27 1.27)
					(thickness 0.15)
				)
				(justify left bottom)
				(hide yes)
			)
		)
		(property "Footprint" "antmicro-footprints:C_0402_1005Metric"
			(at 332.74 212.09 0)
			(effects
				(font
					(size 1.27 1.27)
					(thickness 0.15)
				)
				(justify left bottom)
				(hide yes)
			)
		)
		(property "Datasheet" "https://www.murata.com/products/productdetail?partno=GRM155R61H104KE14%23"
			(at 332.74 209.55 0)
			(effects
				(font
					(size 1.27 1.27)
					(thickness 0.15)
				)
				(justify left bottom)
				(hide yes)
			)
		)
		(property "Description" ""
			(at 353.06 224.79 0)
			(effects
				(font
					(size 1.27 1.27)
				)
			)
		)
		(property "Manufacturer" "Murata"
			(at 332.74 204.47 0)
			(effects
				(font
					(size 1.27 1.27)
					(thickness 0.15)
				)
				(justify left bottom)
				(hide yes)
			)
		)
		(property "MPN" "GRM155R61H104KE14D"
			(at 332.74 207.01 0)
			(effects
				(font
					(size 1.27 1.27)
					(thickness 0.15)
				)
				(justify left bottom)
				(hide yes)
			)
		)
		(property "Val" "100n"
			(at 346.075 223.52 0)
			(effects
				(font
					(size 1.27 1.27)
					(thickness 0.15)
				)
			)
		)
		(property "License" "Apache-2.0"
			(at 332.74 201.93 0)
			(effects
				(font
					(size 1.27 1.27)
					(thickness 0.15)
				)
				(justify left bottom)
				(hide yes)
			)
		)
		(property "Author" "Antmicro"
			(at 332.74 199.39 0)
			(effects
				(font
					(size 1.27 1.27)
					(thickness 0.15)
				)
				(justify left bottom)
				(hide yes)
			)
		)
		(property "Voltage" "50V"
			(at 332.74 196.85 0)
			(effects
				(font
					(size 1.27 1.27)
				)
				(justify left bottom)
				(hide yes)
			)
		)
		(property "Dielectric" "X5R"
			(at 332.74 194.31 0)
			(effects
				(font
					(size 1.27 1.27)
				)
				(justify left bottom)
				(hide yes)
			)
		)
		(pin "1"
		)
		(pin "2"
		)
		(instances
			(project "k410t-devboard"
				(path ""
					(reference "C313")
					(unit 1)
				)
			)
		)
	)
	(symbol
		(lib_id "antmicropower:+3.3V")
		(at 213.36 43.18 0)
		(unit 1)
		(exclude_from_sim no)
		(in_bom yes)
		(on_board yes)
		(dnp no)
		(fields_autoplaced yes)
		(property "Reference" "#PWR0358"
			(at 213.36 46.99 0)
			(effects
				(font
					(size 1.27 1.27)
				)
				(hide yes)
			)
		)
		(property "Value" "+3V3"
			(at 213.36 39.624 0)
			(effects
				(font
					(size 1.27 1.27)
				)
			)
		)
		(property "Footprint" ""
			(at 213.36 43.18 0)
			(effects
				(font
					(size 1.27 1.27)
				)
				(hide yes)
			)
		)
		(property "Datasheet" ""
			(at 213.36 43.18 0)
			(effects
				(font
					(size 1.27 1.27)
				)
				(hide yes)
			)
		)
		(property "Description" ""
			(at 213.36 43.18 0)
			(effects
				(font
					(size 1.27 1.27)
				)
			)
		)
		(pin "1"
		)
		(instances
			(project "k410t-devboard"
				(path ""
					(reference "#PWR0358")
					(unit 1)
				)
			)
		)
	)
	(symbol
		(lib_id "antmicroB2BConnectors:ASP-184329-01_CUSTOM_mounting_holes")
		(at 130.81 184.15 0)
		(unit 3)
		(exclude_from_sim no)
		(in_bom yes)
		(on_board yes)
		(dnp no)
		(fields_autoplaced yes)
		(property "Reference" "J18"
			(at 147.32 170.18 0)
			(effects
				(font
					(size 1.27 1.27)
					(thickness 0.15)
				)
			)
		)
		(property "Value" "ASP-184329-01_mounting_holes"
			(at 147.32 173.355 0)
			(effects
				(font
					(size 1.27 1.27)
					(thickness 0.15)
				)
				(hide yes)
			)
		)
		(property "Footprint" "antmicro-footprints:ASP-184329-01_mounting_holes"
			(at 176.53 195.58 0)
			(effects
				(font
					(size 1.27 1.27)
					(thickness 0.15)
				)
				(justify left bottom)
				(hide yes)
			)
		)
		(property "Datasheet" "https://www.mouser.com/datasheet/2/527/asp_184329_01_mkt-2854128.pdf"
			(at 176.53 198.12 0)
			(effects
				(font
					(size 1.27 1.27)
					(thickness 0.15)
				)
				(justify left bottom)
				(hide yes)
			)
		)
		(property "Description" ""
			(at 130.81 184.15 0)
			(effects
				(font
					(size 1.27 1.27)
				)
			)
		)
		(property "Manufacturer" "Samtec"
			(at 176.53 200.66 0)
			(effects
				(font
					(size 1.27 1.27)
					(thickness 0.15)
				)
				(justify left bottom)
				(hide yes)
			)
		)
		(property "MPN" "ASP-184329-01"
			(at 147.32 172.72 0)
			(effects
				(font
					(size 1.27 1.27)
					(thickness 0.15)
				)
			)
		)
		(property "Author" "Antmicro"
			(at 176.53 205.74 0)
			(effects
				(font
					(size 1.27 1.27)
					(thickness 0.15)
				)
				(justify left bottom)
				(hide yes)
			)
		)
		(property "License" "Apache-2.0"
			(at 176.53 208.28 0)
			(effects
				(font
					(size 1.27 1.27)
					(thickness 0.15)
				)
				(justify left bottom)
				(hide yes)
			)
		)
		(pin "C10"
		)
		(pin "C11"
		)
		(pin "C14"
		)
		(pin "C15"
		)
		(pin "C18"
		)
		(pin "C19"
		)
		(pin "C22"
		)
		(pin "C23"
		)
		(pin "C26"
		)
		(pin "C27"
		)
		(pin "D08"
		)
		(pin "D09"
		)
		(pin "D11"
		)
		(pin "D12"
		)
		(pin "D14"
		)
		(pin "D15"
		)
		(pin "D17"
		)
		(pin "D18"
		)
		(pin "D20"
		)
		(pin "D21"
		)
		(pin "D23"
		)
		(pin "D24"
		)
		(pin "D26"
		)
		(pin "D27"
		)
		(pin "G06"
		)
		(pin "G07"
		)
		(pin "G09"
		)
		(pin "G10"
		)
		(pin "G12"
		)
		(pin "G13"
		)
		(pin "G15"
		)
		(pin "G16"
		)
		(pin "G18"
		)
		(pin "G19"
		)
		(pin "G21"
		)
		(pin "G22"
		)
		(pin "G24"
		)
		(pin "G25"
		)
		(pin "G27"
		)
		(pin "G28"
		)
		(pin "G30"
		)
		(pin "G31"
		)
		(pin "G33"
		)
		(pin "G34"
		)
		(pin "G36"
		)
		(pin "G37"
		)
		(pin "H07"
		)
		(pin "H08"
		)
		(pin "H10"
		)
		(pin "H11"
		)
		(pin "H13"
		)
		(pin "H14"
		)
		(pin "H16"
		)
		(pin "H17"
		)
		(pin "H19"
		)
		(pin "H20"
		)
		(pin "H22"
		)
		(pin "H23"
		)
		(pin "H25"
		)
		(pin "H26"
		)
		(pin "H28"
		)
		(pin "H29"
		)
		(pin "H31"
		)
		(pin "H32"
		)
		(pin "H34"
		)
		(pin "H35"
		)
		(pin "H37"
		)
		(pin "H38"
		)
		(pin "A01"
		)
		(pin "A04"
		)
		(pin "A05"
		)
		(pin "A08"
		)
		(pin "A09"
		)
		(pin "A12"
		)
		(pin "A13"
		)
		(pin "A16"
		)
		(pin "A17"
		)
		(pin "A20"
		)
		(pin "A21"
		)
		(pin "A24"
		)
		(pin "A25"
		)
		(pin "A28"
		)
		(pin "A29"
		)
		(pin "A32"
		)
		(pin "A33"
		)
		(pin "A36"
		)
		(pin "A37"
		)
		(pin "A40"
		)
		(pin "B02"
		)
		(pin "B03"
		)
		(pin "B06"
		)
		(pin "B07"
		)
		(pin "B10"
		)
		(pin "B11"
		)
		(pin "B14"
		)
		(pin "B15"
		)
		(pin "B18"
		)
		(pin "B19"
		)
		(pin "B22"
		)
		(pin "B23"
		)
		(pin "B26"
		)
		(pin "B27"
		)
		(pin "B30"
		)
		(pin "B31"
		)
		(pin "B34"
		)
		(pin "B35"
		)
		(pin "B38"
		)
		(pin "B39"
		)
		(pin "B40"
		)
		(pin "C01"
		)
		(pin "C04"
		)
		(pin "C05"
		)
		(pin "C08"
		)
		(pin "C09"
		)
		(pin "C12"
		)
		(pin "C13"
		)
		(pin "C16"
		)
		(pin "C17"
		)
		(pin "C20"
		)
		(pin "C21"
		)
		(pin "C24"
		)
		(pin "C25"
		)
		(pin "C28"
		)
		(pin "C29"
		)
		(pin "C32"
		)
		(pin "C33"
		)
		(pin "C35"
		)
		(pin "C36"
		)
		(pin "C37"
		)
		(pin "C38"
		)
		(pin "C39"
		)
		(pin "C40"
		)
		(pin "D02"
		)
		(pin "D03"
		)
		(pin "D06"
		)
		(pin "D07"
		)
		(pin "D10"
		)
		(pin "D13"
		)
		(pin "D16"
		)
		(pin "D19"
		)
		(pin "D22"
		)
		(pin "D25"
		)
		(pin "D28"
		)
		(pin "D32"
		)
		(pin "D36"
		)
		(pin "D37"
		)
		(pin "D38"
		)
		(pin "D39"
		)
		(pin "D40"
		)
		(pin "E01"
		)
		(pin "E04"
		)
		(pin "E05"
		)
		(pin "E08"
		)
		(pin "E11"
		)
		(pin "E14"
		)
		(pin "E17"
		)
		(pin "E20"
		)
		(pin "E23"
		)
		(pin "E26"
		)
		(pin "E29"
		)
		(pin "E32"
		)
		(pin "E35"
		)
		(pin "E38"
		)
		(pin "E39"
		)
		(pin "E40"
		)
		(pin "F02"
		)
		(pin "F03"
		)
		(pin "F06"
		)
		(pin "F09"
		)
		(pin "F12"
		)
		(pin "F15"
		)
		(pin "F18"
		)
		(pin "F21"
		)
		(pin "F24"
		)
		(pin "F27"
		)
		(pin "F30"
		)
		(pin "F33"
		)
		(pin "F36"
		)
		(pin "F39"
		)
		(pin "F40"
		)
		(pin "G01"
		)
		(pin "G04"
		)
		(pin "G05"
		)
		(pin "G08"
		)
		(pin "G11"
		)
		(pin "G14"
		)
		(pin "G17"
		)
		(pin "G20"
		)
		(pin "G23"
		)
		(pin "G26"
		)
		(pin "G29"
		)
		(pin "G32"
		)
		(pin "G35"
		)
		(pin "G38"
		)
		(pin "G39"
		)
		(pin "G40"
		)
		(pin "H01"
		)
		(pin "Z34"
		)
		(pin "Z35"
		)
		(pin "Z38"
		)
		(pin "Z39"
		)
		(pin "Z40"
		)
		(pin "C30"
		)
		(pin "H03"
		)
		(pin "H06"
		)
		(pin "H09"
		)
		(pin "H12"
		)
		(pin "H15"
		)
		(pin "H18"
		)
		(pin "H21"
		)
		(pin "H24"
		)
		(pin "H27"
		)
		(pin "H30"
		)
		(pin "H33"
		)
		(pin "H36"
		)
		(pin "H39"
		)
		(pin "H40"
		)
		(pin "J01"
		)
		(pin "J04"
		)
		(pin "J05"
		)
		(pin "J08"
		)
		(pin "J11"
		)
		(pin "J14"
		)
		(pin "J17"
		)
		(pin "J20"
		)
		(pin "J23"
		)
		(pin "J26"
		)
		(pin "J29"
		)
		(pin "J32"
		)
		(pin "J35"
		)
		(pin "J38"
		)
		(pin "J39"
		)
		(pin "J40"
		)
		(pin "K01"
		)
		(pin "K02"
		)
		(pin "K03"
		)
		(pin "K06"
		)
		(pin "K09"
		)
		(pin "K12"
		)
		(pin "K15"
		)
		(pin "K18"
		)
		(pin "K21"
		)
		(pin "K24"
		)
		(pin "K27"
		)
		(pin "K30"
		)
		(pin "K33"
		)
		(pin "K36"
		)
		(pin "K39"
		)
		(pin "K40"
		)
		(pin "L01"
		)
		(pin "L02"
		)
		(pin "L03"
		)
		(pin "L06"
		)
		(pin "L07"
		)
		(pin "L10"
		)
		(pin "L11"
		)
		(pin "L14"
		)
		(pin "L15"
		)
		(pin "L18"
		)
		(pin "L19"
		)
		(pin "L22"
		)
		(pin "L23"
		)
		(pin "L26"
		)
		(pin "L27"
		)
		(pin "L30"
		)
		(pin "L31"
		)
		(pin "L32"
		)
		(pin "L33"
		)
		(pin "L34"
		)
		(pin "L35"
		)
		(pin "L36"
		)
		(pin "L37"
		)
		(pin "L38"
		)
		(pin "L39"
		)
		(pin "L40"
		)
		(pin "M01"
		)
		(pin "M04"
		)
		(pin "M05"
		)
		(pin "M08"
		)
		(pin "M09"
		)
		(pin "M12"
		)
		(pin "M13"
		)
		(pin "M16"
		)
		(pin "M17"
		)
		(pin "M20"
		)
		(pin "M21"
		)
		(pin "M24"
		)
		(pin "M25"
		)
		(pin "M28"
		)
		(pin "M29"
		)
		(pin "M32"
		)
		(pin "M33"
		)
		(pin "M36"
		)
		(pin "M37"
		)
		(pin "M40"
		)
		(pin "Y01"
		)
		(pin "Y04"
		)
		(pin "Y05"
		)
		(pin "Y08"
		)
		(pin "Y09"
		)
		(pin "Y12"
		)
		(pin "Y13"
		)
		(pin "Y16"
		)
		(pin "Y17"
		)
		(pin "Y20"
		)
		(pin "Y21"
		)
		(pin "Y24"
		)
		(pin "Y25"
		)
		(pin "Y28"
		)
		(pin "Y29"
		)
		(pin "Y32"
		)
		(pin "Y33"
		)
		(pin "Y36"
		)
		(pin "Y37"
		)
		(pin "Y40"
		)
		(pin "Z02"
		)
		(pin "Z03"
		)
		(pin "Z06"
		)
		(pin "Z07"
		)
		(pin "Z10"
		)
		(pin "Z11"
		)
		(pin "Z14"
		)
		(pin "Z15"
		)
		(pin "Z18"
		)
		(pin "Z19"
		)
		(pin "Z22"
		)
		(pin "Z23"
		)
		(pin "Z26"
		)
		(pin "Z27"
		)
		(pin "Z30"
		)
		(pin "Z31"
		)
		(pin "M19"
		)
		(pin "M22"
		)
		(pin "M23"
		)
		(pin "M26"
		)
		(pin "M27"
		)
		(pin "M30"
		)
		(pin "M31"
		)
		(pin "M34"
		)
		(pin "M35"
		)
		(pin "M38"
		)
		(pin "C31"
		)
		(pin "C34"
		)
		(pin "D01"
		)
		(pin "D29"
		)
		(pin "D30"
		)
		(pin "D31"
		)
		(pin "D33"
		)
		(pin "D34"
		)
		(pin "D35"
		)
		(pin "F01"
		)
		(pin "H02"
		)
		(pin "Z01"
		)
		(pin "E02"
		)
		(pin "E03"
		)
		(pin "E06"
		)
		(pin "E07"
		)
		(pin "E09"
		)
		(pin "E10"
		)
		(pin "E12"
		)
		(pin "E13"
		)
		(pin "E15"
		)
		(pin "E16"
		)
		(pin "E18"
		)
		(pin "E19"
		)
		(pin "F04"
		)
		(pin "F05"
		)
		(pin "F07"
		)
		(pin "F08"
		)
		(pin "F10"
		)
		(pin "F11"
		)
		(pin "F13"
		)
		(pin "F14"
		)
		(pin "F16"
		)
		(pin "F17"
		)
		(pin "F19"
		)
		(pin "F20"
		)
		(pin "J06"
		)
		(pin "J07"
		)
		(pin "J09"
		)
		(pin "J10"
		)
		(pin "J12"
		)
		(pin "J13"
		)
		(pin "J15"
		)
		(pin "J16"
		)
		(pin "J18"
		)
		(pin "J19"
		)
		(pin "J21"
		)
		(pin "J22"
		)
		(pin "K07"
		)
		(pin "K08"
		)
		(pin "K10"
		)
		(pin "K11"
		)
		(pin "K13"
		)
		(pin "K14"
		)
		(pin "K16"
		)
		(pin "K17"
		)
		(pin "K19"
		)
		(pin "K20"
		)
		(pin "K22"
		)
		(pin "K23"
		)
		(pin "E21"
		)
		(pin "E22"
		)
		(pin "E24"
		)
		(pin "E25"
		)
		(pin "E27"
		)
		(pin "E28"
		)
		(pin "E30"
		)
		(pin "E31"
		)
		(pin "E33"
		)
		(pin "E34"
		)
		(pin "E36"
		)
		(pin "E37"
		)
		(pin "F22"
		)
		(pin "F23"
		)
		(pin "F25"
		)
		(pin "F26"
		)
		(pin "F28"
		)
		(pin "F29"
		)
		(pin "F31"
		)
		(pin "F32"
		)
		(pin "F34"
		)
		(pin "F35"
		)
		(pin "F37"
		)
		(pin "F38"
		)
		(pin "J24"
		)
		(pin "J25"
		)
		(pin "J27"
		)
		(pin "J28"
		)
		(pin "J30"
		)
		(pin "J31"
		)
		(pin "J33"
		)
		(pin "J34"
		)
		(pin "J36"
		)
		(pin "J37"
		)
		(pin "K25"
		)
		(pin "K26"
		)
		(pin "K28"
		)
		(pin "K29"
		)
		(pin "K31"
		)
		(pin "K32"
		)
		(pin "K34"
		)
		(pin "K35"
		)
		(pin "K37"
		)
		(pin "K38"
		)
		(pin "B01"
		)
		(pin "G02"
		)
		(pin "G03"
		)
		(pin "H04"
		)
		(pin "H05"
		)
		(pin "J02"
		)
		(pin "J03"
		)
		(pin "K04"
		)
		(pin "K05"
		)
		(pin "B20"
		)
		(pin "B21"
		)
		(pin "D04"
		)
		(pin "D05"
		)
		(pin "L04"
		)
		(pin "L05"
		)
		(pin "L08"
		)
		(pin "L09"
		)
		(pin "L12"
		)
		(pin "L13"
		)
		(pin "L16"
		)
		(pin "L17"
		)
		(pin "L20"
		)
		(pin "L21"
		)
		(pin "L24"
		)
		(pin "L25"
		)
		(pin "L28"
		)
		(pin "L29"
		)
		(pin "Z20"
		)
		(pin "Z21"
		)
		(pin "A02"
		)
		(pin "A03"
		)
		(pin "A06"
		)
		(pin "A07"
		)
		(pin "A10"
		)
		(pin "A11"
		)
		(pin "A14"
		)
		(pin "A15"
		)
		(pin "A18"
		)
		(pin "A19"
		)
		(pin "A22"
		)
		(pin "A23"
		)
		(pin "A26"
		)
		(pin "A27"
		)
		(pin "A30"
		)
		(pin "A31"
		)
		(pin "A34"
		)
		(pin "A35"
		)
		(pin "A38"
		)
		(pin "A39"
		)
		(pin "B04"
		)
		(pin "B05"
		)
		(pin "B08"
		)
		(pin "B09"
		)
		(pin "B12"
		)
		(pin "B13"
		)
		(pin "B16"
		)
		(pin "B17"
		)
		(pin "B24"
		)
		(pin "B25"
		)
		(pin "B28"
		)
		(pin "B29"
		)
		(pin "B32"
		)
		(pin "B33"
		)
		(pin "B36"
		)
		(pin "B37"
		)
		(pin "C02"
		)
		(pin "C03"
		)
		(pin "C06"
		)
		(pin "C07"
		)
		(pin "M02"
		)
		(pin "M03"
		)
		(pin "M06"
		)
		(pin "M07"
		)
		(pin "M10"
		)
		(pin "M11"
		)
		(pin "M14"
		)
		(pin "M15"
		)
		(pin "M18"
		)
		(pin "M39"
		)
		(pin "Y02"
		)
		(pin "Y03"
		)
		(pin "Y06"
		)
		(pin "Y07"
		)
		(pin "Y10"
		)
		(pin "Y11"
		)
		(pin "Y14"
		)
		(pin "Y15"
		)
		(pin "Y18"
		)
		(pin "Y19"
		)
		(pin "Y22"
		)
		(pin "Y23"
		)
		(pin "Y26"
		)
		(pin "Y27"
		)
		(pin "Y30"
		)
		(pin "Y31"
		)
		(pin "Y34"
		)
		(pin "Y35"
		)
		(pin "Y38"
		)
		(pin "Y39"
		)
		(pin "Z04"
		)
		(pin "Z05"
		)
		(pin "Z08"
		)
		(pin "Z09"
		)
		(pin "Z12"
		)
		(pin "Z13"
		)
		(pin "Z16"
		)
		(pin "Z17"
		)
		(pin "Z24"
		)
		(pin "Z25"
		)
		(pin "Z28"
		)
		(pin "Z29"
		)
		(pin "Z32"
		)
		(pin "Z33"
		)
		(pin "Z36"
		)
		(pin "Z37"
		)
		(instances
			(project "k410t-devboard"
				(path ""
					(reference "J18")
					(unit 3)
				)
			)
		)
	)
	(symbol
		(lib_id "antmicroCapacitors0402:C_100n_0402")
		(at 353.06 179.07 180)
		(unit 1)
		(exclude_from_sim no)
		(in_bom yes)
		(on_board yes)
		(dnp no)
		(property "Reference" "C304"
			(at 355.6 177.8 0)
			(effects
				(font
					(size 1.27 1.27)
				)
			)
		)
		(property "Value" "C_100n_0402"
			(at 332.74 168.91 0)
			(effects
				(font
					(size 1.27 1.27)
					(thickness 0.15)
				)
				(justify left bottom)
				(hide yes)
			)
		)
		(property "Footprint" "antmicro-footprints:C_0402_1005Metric"
			(at 332.74 166.37 0)
			(effects
				(font
					(size 1.27 1.27)
					(thickness 0.15)
				)
				(justify left bottom)
				(hide yes)
			)
		)
		(property "Datasheet" "https://www.murata.com/products/productdetail?partno=GRM155R61H104KE14%23"
			(at 332.74 163.83 0)
			(effects
				(font
					(size 1.27 1.27)
					(thickness 0.15)
				)
				(justify left bottom)
				(hide yes)
			)
		)
		(property "Description" ""
			(at 353.06 179.07 0)
			(effects
				(font
					(size 1.27 1.27)
				)
			)
		)
		(property "Manufacturer" "Murata"
			(at 332.74 158.75 0)
			(effects
				(font
					(size 1.27 1.27)
					(thickness 0.15)
				)
				(justify left bottom)
				(hide yes)
			)
		)
		(property "MPN" "GRM155R61H104KE14D"
			(at 332.74 161.29 0)
			(effects
				(font
					(size 1.27 1.27)
					(thickness 0.15)
				)
				(justify left bottom)
				(hide yes)
			)
		)
		(property "Val" "100n"
			(at 346.075 177.165 0)
			(effects
				(font
					(size 1.27 1.27)
					(thickness 0.15)
				)
			)
		)
		(property "License" "Apache-2.0"
			(at 332.74 156.21 0)
			(effects
				(font
					(size 1.27 1.27)
					(thickness 0.15)
				)
				(justify left bottom)
				(hide yes)
			)
		)
		(property "Author" "Antmicro"
			(at 332.74 153.67 0)
			(effects
				(font
					(size 1.27 1.27)
					(thickness 0.15)
				)
				(justify left bottom)
				(hide yes)
			)
		)
		(property "Voltage" "50V"
			(at 332.74 151.13 0)
			(effects
				(font
					(size 1.27 1.27)
				)
				(justify left bottom)
				(hide yes)
			)
		)
		(property "Dielectric" "X5R"
			(at 332.74 148.59 0)
			(effects
				(font
					(size 1.27 1.27)
				)
				(justify left bottom)
				(hide yes)
			)
		)
		(pin "1"
		)
		(pin "2"
		)
		(instances
			(project "k410t-devboard"
				(path ""
					(reference "C304")
					(unit 1)
				)
			)
		)
	)
	(symbol
		(lib_id "antmicroResistors0402:R_33R_0402")
		(at 349.25 41.91 0)
		(unit 1)
		(exclude_from_sim no)
		(in_bom yes)
		(on_board yes)
		(dnp no)
		(property "Reference" "R271"
			(at 356.87 40.64 0)
			(effects
				(font
					(size 1.27 1.27)
				)
			)
		)
		(property "Value" "R_33R_0402"
			(at 369.57 54.61 0)
			(effects
				(font
					(size 1.27 1.27)
					(thickness 0.15)
				)
				(justify left bottom)
				(hide yes)
			)
		)
		(property "Footprint" "antmicro-footprints:R_0402_1005Metric"
			(at 369.57 57.15 0)
			(effects
				(font
					(size 1.27 1.27)
					(thickness 0.15)
				)
				(justify left bottom)
				(hide yes)
			)
		)
		(property "Datasheet" "https://www.bourns.com/docs/product-datasheets/cr.pdf"
			(at 369.57 59.69 0)
			(effects
				(font
					(size 1.27 1.27)
					(thickness 0.15)
				)
				(justify left bottom)
				(hide yes)
			)
		)
		(property "Description" ""
			(at 349.25 41.91 0)
			(effects
				(font
					(size 1.27 1.27)
				)
			)
		)
		(property "Manufacturer" "Bourns"
			(at 369.57 64.77 0)
			(effects
				(font
					(size 1.27 1.27)
					(thickness 0.15)
				)
				(justify left bottom)
				(hide yes)
			)
		)
		(property "MPN" "CR0402-FX-33R0GLF"
			(at 369.57 62.23 0)
			(effects
				(font
					(size 1.27 1.27)
					(thickness 0.15)
				)
				(justify left bottom)
				(hide yes)
			)
		)
		(property "Val" "33R"
			(at 347.345 40.64 0)
			(effects
				(font
					(size 1.27 1.27)
					(thickness 0.15)
				)
			)
		)
		(property "License" "Apache-2.0"
			(at 369.57 67.31 0)
			(effects
				(font
					(size 1.27 1.27)
					(thickness 0.15)
				)
				(justify left bottom)
				(hide yes)
			)
		)
		(property "Author" "Antmicro"
			(at 369.57 69.85 0)
			(effects
				(font
					(size 1.27 1.27)
					(thickness 0.15)
				)
				(justify left bottom)
				(hide yes)
			)
		)
		(property "Tolerance" "1%"
			(at 369.57 52.07 0)
			(effects
				(font
					(size 1.27 1.27)
				)
				(justify left bottom)
				(hide yes)
			)
		)
		(pin "1"
		)
		(pin "2"
		)
		(instances
			(project "k410t-devboard"
				(path ""
					(reference "R271")
					(unit 1)
				)
			)
		)
	)
	(symbol
		(lib_id "antmicroB2BConnectors:ASP-184329-01_CUSTOM_mounting_holes")
		(at 67.31 38.1 0)
		(unit 1)
		(exclude_from_sim no)
		(in_bom yes)
		(on_board yes)
		(dnp no)
		(fields_autoplaced yes)
		(property "Reference" "J18"
			(at 82.55 26.67 0)
			(effects
				(font
					(size 1.27 1.27)
					(thickness 0.15)
				)
			)
		)
		(property "Value" "ASP-184329-01_CUSTOM_mounting_holes"
			(at 82.55 29.845 0)
			(effects
				(font
					(size 1.27 1.27)
					(thickness 0.15)
				)
				(hide yes)
			)
		)
		(property "Footprint" "antmicro-footprints:ASP-184329-01_mounting_holes"
			(at 113.03 49.53 0)
			(effects
				(font
					(size 1.27 1.27)
					(thickness 0.15)
				)
				(justify left bottom)
				(hide yes)
			)
		)
		(property "Datasheet" "https://www.mouser.com/datasheet/2/527/asp_184329_01_mkt-2854128.pdf"
			(at 113.03 52.07 0)
			(effects
				(font
					(size 1.27 1.27)
					(thickness 0.15)
				)
				(justify left bottom)
				(hide yes)
			)
		)
		(property "Description" ""
			(at 67.31 38.1 0)
			(effects
				(font
					(size 1.27 1.27)
				)
			)
		)
		(property "Manufacturer" "Samtec"
			(at 113.03 54.61 0)
			(effects
				(font
					(size 1.27 1.27)
					(thickness 0.15)
				)
				(justify left bottom)
				(hide yes)
			)
		)
		(property "MPN" "ASP-184329-01"
			(at 82.55 29.21 0)
			(effects
				(font
					(size 1.27 1.27)
					(thickness 0.15)
				)
			)
		)
		(property "Author" "Antmicro"
			(at 113.03 59.69 0)
			(effects
				(font
					(size 1.27 1.27)
					(thickness 0.15)
				)
				(justify left bottom)
				(hide yes)
			)
		)
		(property "License" "Apache-2.0"
			(at 113.03 62.23 0)
			(effects
				(font
					(size 1.27 1.27)
					(thickness 0.15)
				)
				(justify left bottom)
				(hide yes)
			)
		)
		(pin "A01"
		)
		(pin "A04"
		)
		(pin "A05"
		)
		(pin "A08"
		)
		(pin "A09"
		)
		(pin "A12"
		)
		(pin "A13"
		)
		(pin "A16"
		)
		(pin "A17"
		)
		(pin "A20"
		)
		(pin "A21"
		)
		(pin "A24"
		)
		(pin "A25"
		)
		(pin "A28"
		)
		(pin "A29"
		)
		(pin "A32"
		)
		(pin "A33"
		)
		(pin "A36"
		)
		(pin "A37"
		)
		(pin "A40"
		)
		(pin "B02"
		)
		(pin "B03"
		)
		(pin "B06"
		)
		(pin "B07"
		)
		(pin "B10"
		)
		(pin "B11"
		)
		(pin "B14"
		)
		(pin "B15"
		)
		(pin "B18"
		)
		(pin "B19"
		)
		(pin "B22"
		)
		(pin "B23"
		)
		(pin "B26"
		)
		(pin "B27"
		)
		(pin "B30"
		)
		(pin "B31"
		)
		(pin "B34"
		)
		(pin "B35"
		)
		(pin "B38"
		)
		(pin "B39"
		)
		(pin "B40"
		)
		(pin "C01"
		)
		(pin "C04"
		)
		(pin "C05"
		)
		(pin "C08"
		)
		(pin "C09"
		)
		(pin "C12"
		)
		(pin "C13"
		)
		(pin "C16"
		)
		(pin "C17"
		)
		(pin "C20"
		)
		(pin "C21"
		)
		(pin "C24"
		)
		(pin "C25"
		)
		(pin "C28"
		)
		(pin "C29"
		)
		(pin "C32"
		)
		(pin "C33"
		)
		(pin "C35"
		)
		(pin "C36"
		)
		(pin "C37"
		)
		(pin "C38"
		)
		(pin "C39"
		)
		(pin "C40"
		)
		(pin "D02"
		)
		(pin "D03"
		)
		(pin "D06"
		)
		(pin "D07"
		)
		(pin "D10"
		)
		(pin "D13"
		)
		(pin "D16"
		)
		(pin "D19"
		)
		(pin "D22"
		)
		(pin "D25"
		)
		(pin "D28"
		)
		(pin "D32"
		)
		(pin "D36"
		)
		(pin "D37"
		)
		(pin "D38"
		)
		(pin "D39"
		)
		(pin "D40"
		)
		(pin "E01"
		)
		(pin "E04"
		)
		(pin "E05"
		)
		(pin "E08"
		)
		(pin "E11"
		)
		(pin "E14"
		)
		(pin "E17"
		)
		(pin "E20"
		)
		(pin "E23"
		)
		(pin "E26"
		)
		(pin "E29"
		)
		(pin "E32"
		)
		(pin "E35"
		)
		(pin "E38"
		)
		(pin "E39"
		)
		(pin "E40"
		)
		(pin "F02"
		)
		(pin "F03"
		)
		(pin "F06"
		)
		(pin "F09"
		)
		(pin "F12"
		)
		(pin "F15"
		)
		(pin "F18"
		)
		(pin "F21"
		)
		(pin "F24"
		)
		(pin "F27"
		)
		(pin "F30"
		)
		(pin "F33"
		)
		(pin "F36"
		)
		(pin "F39"
		)
		(pin "F40"
		)
		(pin "G01"
		)
		(pin "G04"
		)
		(pin "G05"
		)
		(pin "G08"
		)
		(pin "G11"
		)
		(pin "G14"
		)
		(pin "G17"
		)
		(pin "G20"
		)
		(pin "G23"
		)
		(pin "G26"
		)
		(pin "G29"
		)
		(pin "G32"
		)
		(pin "G35"
		)
		(pin "G38"
		)
		(pin "G39"
		)
		(pin "G40"
		)
		(pin "H01"
		)
		(pin "H03"
		)
		(pin "H06"
		)
		(pin "H09"
		)
		(pin "H12"
		)
		(pin "H15"
		)
		(pin "H18"
		)
		(pin "H21"
		)
		(pin "H24"
		)
		(pin "H27"
		)
		(pin "H30"
		)
		(pin "H33"
		)
		(pin "H36"
		)
		(pin "H39"
		)
		(pin "H40"
		)
		(pin "J01"
		)
		(pin "J04"
		)
		(pin "J05"
		)
		(pin "J08"
		)
		(pin "J11"
		)
		(pin "J14"
		)
		(pin "J17"
		)
		(pin "J20"
		)
		(pin "J23"
		)
		(pin "J26"
		)
		(pin "J29"
		)
		(pin "J32"
		)
		(pin "J35"
		)
		(pin "J38"
		)
		(pin "J39"
		)
		(pin "J40"
		)
		(pin "K01"
		)
		(pin "K02"
		)
		(pin "K03"
		)
		(pin "K06"
		)
		(pin "K09"
		)
		(pin "K12"
		)
		(pin "K15"
		)
		(pin "K18"
		)
		(pin "K21"
		)
		(pin "K24"
		)
		(pin "K27"
		)
		(pin "K30"
		)
		(pin "K33"
		)
		(pin "K36"
		)
		(pin "K39"
		)
		(pin "K40"
		)
		(pin "L01"
		)
		(pin "L02"
		)
		(pin "L03"
		)
		(pin "L06"
		)
		(pin "L07"
		)
		(pin "L10"
		)
		(pin "L11"
		)
		(pin "L14"
		)
		(pin "L15"
		)
		(pin "L18"
		)
		(pin "L19"
		)
		(pin "L22"
		)
		(pin "L23"
		)
		(pin "L26"
		)
		(pin "L27"
		)
		(pin "L30"
		)
		(pin "L31"
		)
		(pin "L32"
		)
		(pin "L33"
		)
		(pin "L34"
		)
		(pin "L35"
		)
		(pin "L36"
		)
		(pin "L37"
		)
		(pin "L38"
		)
		(pin "L39"
		)
		(pin "L40"
		)
		(pin "M01"
		)
		(pin "M04"
		)
		(pin "M05"
		)
		(pin "M08"
		)
		(pin "M09"
		)
		(pin "M12"
		)
		(pin "M13"
		)
		(pin "M16"
		)
		(pin "M17"
		)
		(pin "M20"
		)
		(pin "M21"
		)
		(pin "M24"
		)
		(pin "M25"
		)
		(pin "M28"
		)
		(pin "M29"
		)
		(pin "M32"
		)
		(pin "M33"
		)
		(pin "M36"
		)
		(pin "M37"
		)
		(pin "M40"
		)
		(pin "Y01"
		)
		(pin "Y04"
		)
		(pin "Y05"
		)
		(pin "Y08"
		)
		(pin "Y09"
		)
		(pin "Y12"
		)
		(pin "Y13"
		)
		(pin "Y16"
		)
		(pin "Y17"
		)
		(pin "Y20"
		)
		(pin "Y21"
		)
		(pin "Y24"
		)
		(pin "Y25"
		)
		(pin "Y28"
		)
		(pin "Y29"
		)
		(pin "Y32"
		)
		(pin "Y33"
		)
		(pin "Y36"
		)
		(pin "Y37"
		)
		(pin "Y40"
		)
		(pin "Z02"
		)
		(pin "Z03"
		)
		(pin "Z06"
		)
		(pin "Z07"
		)
		(pin "Z10"
		)
		(pin "Z11"
		)
		(pin "Z14"
		)
		(pin "Z15"
		)
		(pin "Z18"
		)
		(pin "Z19"
		)
		(pin "Z22"
		)
		(pin "Z23"
		)
		(pin "Z26"
		)
		(pin "Z27"
		)
		(pin "Z30"
		)
		(pin "Z31"
		)
		(pin "Z34"
		)
		(pin "Z35"
		)
		(pin "Z38"
		)
		(pin "Z39"
		)
		(pin "Z40"
		)
		(pin "C30"
		)
		(pin "M19"
		)
		(pin "M22"
		)
		(pin "M23"
		)
		(pin "M26"
		)
		(pin "M27"
		)
		(pin "M30"
		)
		(pin "M31"
		)
		(pin "M34"
		)
		(pin "M35"
		)
		(pin "M38"
		)
		(pin "C31"
		)
		(pin "C34"
		)
		(pin "D01"
		)
		(pin "D29"
		)
		(pin "D30"
		)
		(pin "D31"
		)
		(pin "D33"
		)
		(pin "D34"
		)
		(pin "D35"
		)
		(pin "F01"
		)
		(pin "H02"
		)
		(pin "Z01"
		)
		(pin "C10"
		)
		(pin "C11"
		)
		(pin "C14"
		)
		(pin "C15"
		)
		(pin "C18"
		)
		(pin "C19"
		)
		(pin "C22"
		)
		(pin "C23"
		)
		(pin "C26"
		)
		(pin "C27"
		)
		(pin "D08"
		)
		(pin "D09"
		)
		(pin "D11"
		)
		(pin "D12"
		)
		(pin "D14"
		)
		(pin "D15"
		)
		(pin "D17"
		)
		(pin "D18"
		)
		(pin "D20"
		)
		(pin "D21"
		)
		(pin "D23"
		)
		(pin "D24"
		)
		(pin "D26"
		)
		(pin "D27"
		)
		(pin "G06"
		)
		(pin "G07"
		)
		(pin "G09"
		)
		(pin "G10"
		)
		(pin "G12"
		)
		(pin "G13"
		)
		(pin "G15"
		)
		(pin "G16"
		)
		(pin "G18"
		)
		(pin "G19"
		)
		(pin "G21"
		)
		(pin "G22"
		)
		(pin "G24"
		)
		(pin "G25"
		)
		(pin "G27"
		)
		(pin "G28"
		)
		(pin "G30"
		)
		(pin "G31"
		)
		(pin "G33"
		)
		(pin "G34"
		)
		(pin "G36"
		)
		(pin "G37"
		)
		(pin "H07"
		)
		(pin "H08"
		)
		(pin "H10"
		)
		(pin "H11"
		)
		(pin "H13"
		)
		(pin "H14"
		)
		(pin "H16"
		)
		(pin "H17"
		)
		(pin "H19"
		)
		(pin "H20"
		)
		(pin "H22"
		)
		(pin "H23"
		)
		(pin "H25"
		)
		(pin "H26"
		)
		(pin "H28"
		)
		(pin "H29"
		)
		(pin "H31"
		)
		(pin "H32"
		)
		(pin "H34"
		)
		(pin "H35"
		)
		(pin "H37"
		)
		(pin "H38"
		)
		(pin "E02"
		)
		(pin "E03"
		)
		(pin "E06"
		)
		(pin "E07"
		)
		(pin "E09"
		)
		(pin "E10"
		)
		(pin "E12"
		)
		(pin "E13"
		)
		(pin "E15"
		)
		(pin "E16"
		)
		(pin "E18"
		)
		(pin "E19"
		)
		(pin "F04"
		)
		(pin "F05"
		)
		(pin "F07"
		)
		(pin "F08"
		)
		(pin "F10"
		)
		(pin "F11"
		)
		(pin "F13"
		)
		(pin "F14"
		)
		(pin "F16"
		)
		(pin "F17"
		)
		(pin "F19"
		)
		(pin "F20"
		)
		(pin "J06"
		)
		(pin "J07"
		)
		(pin "J09"
		)
		(pin "J10"
		)
		(pin "J12"
		)
		(pin "J13"
		)
		(pin "J15"
		)
		(pin "J16"
		)
		(pin "J18"
		)
		(pin "J19"
		)
		(pin "J21"
		)
		(pin "J22"
		)
		(pin "K07"
		)
		(pin "K08"
		)
		(pin "K10"
		)
		(pin "K11"
		)
		(pin "K13"
		)
		(pin "K14"
		)
		(pin "K16"
		)
		(pin "K17"
		)
		(pin "K19"
		)
		(pin "K20"
		)
		(pin "K22"
		)
		(pin "K23"
		)
		(pin "E21"
		)
		(pin "E22"
		)
		(pin "E24"
		)
		(pin "E25"
		)
		(pin "E27"
		)
		(pin "E28"
		)
		(pin "E30"
		)
		(pin "E31"
		)
		(pin "E33"
		)
		(pin "E34"
		)
		(pin "E36"
		)
		(pin "E37"
		)
		(pin "F22"
		)
		(pin "F23"
		)
		(pin "F25"
		)
		(pin "F26"
		)
		(pin "F28"
		)
		(pin "F29"
		)
		(pin "F31"
		)
		(pin "F32"
		)
		(pin "F34"
		)
		(pin "F35"
		)
		(pin "F37"
		)
		(pin "F38"
		)
		(pin "J24"
		)
		(pin "J25"
		)
		(pin "J27"
		)
		(pin "J28"
		)
		(pin "J30"
		)
		(pin "J31"
		)
		(pin "J33"
		)
		(pin "J34"
		)
		(pin "J36"
		)
		(pin "J37"
		)
		(pin "K25"
		)
		(pin "K26"
		)
		(pin "K28"
		)
		(pin "K29"
		)
		(pin "K31"
		)
		(pin "K32"
		)
		(pin "K34"
		)
		(pin "K35"
		)
		(pin "K37"
		)
		(pin "K38"
		)
		(pin "B01"
		)
		(pin "G02"
		)
		(pin "G03"
		)
		(pin "H04"
		)
		(pin "H05"
		)
		(pin "J02"
		)
		(pin "J03"
		)
		(pin "K04"
		)
		(pin "K05"
		)
		(pin "B20"
		)
		(pin "B21"
		)
		(pin "D04"
		)
		(pin "D05"
		)
		(pin "L04"
		)
		(pin "L05"
		)
		(pin "L08"
		)
		(pin "L09"
		)
		(pin "L12"
		)
		(pin "L13"
		)
		(pin "L16"
		)
		(pin "L17"
		)
		(pin "L20"
		)
		(pin "L21"
		)
		(pin "L24"
		)
		(pin "L25"
		)
		(pin "L28"
		)
		(pin "L29"
		)
		(pin "Z20"
		)
		(pin "Z21"
		)
		(pin "A02"
		)
		(pin "A03"
		)
		(pin "A06"
		)
		(pin "A07"
		)
		(pin "A10"
		)
		(pin "A11"
		)
		(pin "A14"
		)
		(pin "A15"
		)
		(pin "A18"
		)
		(pin "A19"
		)
		(pin "A22"
		)
		(pin "A23"
		)
		(pin "A26"
		)
		(pin "A27"
		)
		(pin "A30"
		)
		(pin "A31"
		)
		(pin "A34"
		)
		(pin "A35"
		)
		(pin "A38"
		)
		(pin "A39"
		)
		(pin "B04"
		)
		(pin "B05"
		)
		(pin "B08"
		)
		(pin "B09"
		)
		(pin "B12"
		)
		(pin "B13"
		)
		(pin "B16"
		)
		(pin "B17"
		)
		(pin "B24"
		)
		(pin "B25"
		)
		(pin "B28"
		)
		(pin "B29"
		)
		(pin "B32"
		)
		(pin "B33"
		)
		(pin "B36"
		)
		(pin "B37"
		)
		(pin "C02"
		)
		(pin "C03"
		)
		(pin "C06"
		)
		(pin "C07"
		)
		(pin "M02"
		)
		(pin "M03"
		)
		(pin "M06"
		)
		(pin "M07"
		)
		(pin "M10"
		)
		(pin "M11"
		)
		(pin "M14"
		)
		(pin "M15"
		)
		(pin "M18"
		)
		(pin "M39"
		)
		(pin "Y02"
		)
		(pin "Y03"
		)
		(pin "Y06"
		)
		(pin "Y07"
		)
		(pin "Y10"
		)
		(pin "Y11"
		)
		(pin "Y14"
		)
		(pin "Y15"
		)
		(pin "Y18"
		)
		(pin "Y19"
		)
		(pin "Y22"
		)
		(pin "Y23"
		)
		(pin "Y26"
		)
		(pin "Y27"
		)
		(pin "Y30"
		)
		(pin "Y31"
		)
		(pin "Y34"
		)
		(pin "Y35"
		)
		(pin "Y38"
		)
		(pin "Y39"
		)
		(pin "Z04"
		)
		(pin "Z05"
		)
		(pin "Z08"
		)
		(pin "Z09"
		)
		(pin "Z12"
		)
		(pin "Z13"
		)
		(pin "Z16"
		)
		(pin "Z17"
		)
		(pin "Z24"
		)
		(pin "Z25"
		)
		(pin "Z28"
		)
		(pin "Z29"
		)
		(pin "Z32"
		)
		(pin "Z33"
		)
		(pin "Z36"
		)
		(pin "Z37"
		)
		(instances
			(project "k410t-devboard"
				(path ""
					(reference "J18")
					(unit 1)
				)
			)
		)
	)
	(symbol
		(lib_id "antmicroResistors0402:R_10k_0402")
		(at 111.76 185.42 90)
		(unit 1)
		(exclude_from_sim no)
		(in_bom yes)
		(on_board yes)
		(dnp no)
		(fields_autoplaced yes)
		(property "Reference" "R265"
			(at 113.665 181.6099 90)
			(effects
				(font
					(size 1.27 1.27)
				)
				(justify right)
			)
		)
		(property "Value" "R_10k_0402"
			(at 124.46 165.1 0)
			(effects
				(font
					(size 1.27 1.27)
					(thickness 0.15)
				)
				(justify left bottom)
				(hide yes)
			)
		)
		(property "Footprint" "antmicro-footprints:R_0402_1005Metric"
			(at 127 165.1 0)
			(effects
				(font
					(size 1.27 1.27)
					(thickness 0.15)
				)
				(justify left bottom)
				(hide yes)
			)
		)
		(property "Datasheet" "https://www.bourns.com/docs/product-datasheets/cr.pdf"
			(at 129.54 165.1 0)
			(effects
				(font
					(size 1.27 1.27)
					(thickness 0.15)
				)
				(justify left bottom)
				(hide yes)
			)
		)
		(property "Description" ""
			(at 111.76 185.42 0)
			(effects
				(font
					(size 1.27 1.27)
				)
			)
		)
		(property "Manufacturer" "Bourns"
			(at 134.62 165.1 0)
			(effects
				(font
					(size 1.27 1.27)
					(thickness 0.15)
				)
				(justify left bottom)
				(hide yes)
			)
		)
		(property "MPN" "CR0402-FX-1002GLF"
			(at 132.08 165.1 0)
			(effects
				(font
					(size 1.27 1.27)
					(thickness 0.15)
				)
				(justify left bottom)
				(hide yes)
			)
		)
		(property "Val" "10k"
			(at 113.665 184.1499 90)
			(effects
				(font
					(size 1.27 1.27)
					(thickness 0.15)
				)
				(justify right)
			)
		)
		(property "License" "Apache-2.0"
			(at 137.16 165.1 0)
			(effects
				(font
					(size 1.27 1.27)
					(thickness 0.15)
				)
				(justify left bottom)
				(hide yes)
			)
		)
		(property "Author" "Antmicro"
			(at 139.7 165.1 0)
			(effects
				(font
					(size 1.27 1.27)
					(thickness 0.15)
				)
				(justify left bottom)
				(hide yes)
			)
		)
		(property "Tolerance" "1%"
			(at 121.92 165.1 0)
			(effects
				(font
					(size 1.27 1.27)
				)
				(justify left bottom)
				(hide yes)
			)
		)
		(pin "1"
		)
		(pin "2"
		)
		(instances
			(project "k410t-devboard"
				(path ""
					(reference "R265")
					(unit 1)
				)
			)
		)
	)
	(symbol
		(lib_id "antmicroResistors0402:R_33R_0402")
		(at 349.25 52.07 0)
		(unit 1)
		(exclude_from_sim no)
		(in_bom yes)
		(on_board yes)
		(dnp no)
		(property "Reference" "R273"
			(at 356.87 50.8 0)
			(effects
				(font
					(size 1.27 1.27)
				)
			)
		)
		(property "Value" "R_33R_0402"
			(at 369.57 64.77 0)
			(effects
				(font
					(size 1.27 1.27)
					(thickness 0.15)
				)
				(justify left bottom)
				(hide yes)
			)
		)
		(property "Footprint" "antmicro-footprints:R_0402_1005Metric"
			(at 369.57 67.31 0)
			(effects
				(font
					(size 1.27 1.27)
					(thickness 0.15)
				)
				(justify left bottom)
				(hide yes)
			)
		)
		(property "Datasheet" "https://www.bourns.com/docs/product-datasheets/cr.pdf"
			(at 369.57 69.85 0)
			(effects
				(font
					(size 1.27 1.27)
					(thickness 0.15)
				)
				(justify left bottom)
				(hide yes)
			)
		)
		(property "Description" ""
			(at 349.25 52.07 0)
			(effects
				(font
					(size 1.27 1.27)
				)
			)
		)
		(property "Manufacturer" "Bourns"
			(at 369.57 74.93 0)
			(effects
				(font
					(size 1.27 1.27)
					(thickness 0.15)
				)
				(justify left bottom)
				(hide yes)
			)
		)
		(property "MPN" "CR0402-FX-33R0GLF"
			(at 369.57 72.39 0)
			(effects
				(font
					(size 1.27 1.27)
					(thickness 0.15)
				)
				(justify left bottom)
				(hide yes)
			)
		)
		(property "Val" "33R"
			(at 347.345 50.8 0)
			(effects
				(font
					(size 1.27 1.27)
					(thickness 0.15)
				)
			)
		)
		(property "License" "Apache-2.0"
			(at 369.57 77.47 0)
			(effects
				(font
					(size 1.27 1.27)
					(thickness 0.15)
				)
				(justify left bottom)
				(hide yes)
			)
		)
		(property "Author" "Antmicro"
			(at 369.57 80.01 0)
			(effects
				(font
					(size 1.27 1.27)
					(thickness 0.15)
				)
				(justify left bottom)
				(hide yes)
			)
		)
		(property "Tolerance" "1%"
			(at 369.57 62.23 0)
			(effects
				(font
					(size 1.27 1.27)
				)
				(justify left bottom)
				(hide yes)
			)
		)
		(pin "1"
		)
		(pin "2"
		)
		(instances
			(project "k410t-devboard"
				(path ""
					(reference "R273")
					(unit 1)
				)
			)
		)
	)
	(symbol
		(lib_id "antmicropower:+3.3V")
		(at 203.2 43.18 0)
		(unit 1)
		(exclude_from_sim no)
		(in_bom yes)
		(on_board yes)
		(dnp no)
		(fields_autoplaced yes)
		(property "Reference" "#PWR0355"
			(at 203.2 46.99 0)
			(effects
				(font
					(size 1.27 1.27)
				)
				(hide yes)
			)
		)
		(property "Value" "+3V3"
			(at 203.2 39.624 0)
			(effects
				(font
					(size 1.27 1.27)
				)
			)
		)
		(property "Footprint" ""
			(at 203.2 43.18 0)
			(effects
				(font
					(size 1.27 1.27)
				)
				(hide yes)
			)
		)
		(property "Datasheet" ""
			(at 203.2 43.18 0)
			(effects
				(font
					(size 1.27 1.27)
				)
				(hide yes)
			)
		)
		(property "Description" ""
			(at 203.2 43.18 0)
			(effects
				(font
					(size 1.27 1.27)
				)
			)
		)
		(pin "1"
		)
		(instances
			(project "k410t-devboard"
				(path ""
					(reference "#PWR0355")
					(unit 1)
				)
			)
		)
	)
	(symbol
		(lib_id "antmicropower:+3.3V")
		(at 130.81 26.67 0)
		(unit 1)
		(exclude_from_sim no)
		(in_bom yes)
		(on_board yes)
		(dnp no)
		(fields_autoplaced yes)
		(property "Reference" "#PWR0505"
			(at 130.81 30.48 0)
			(effects
				(font
					(size 1.27 1.27)
				)
				(hide yes)
			)
		)
		(property "Value" "+3V3"
			(at 130.81 23.114 0)
			(effects
				(font
					(size 1.27 1.27)
				)
			)
		)
		(property "Footprint" ""
			(at 130.81 26.67 0)
			(effects
				(font
					(size 1.27 1.27)
				)
				(hide yes)
			)
		)
		(property "Datasheet" ""
			(at 130.81 26.67 0)
			(effects
				(font
					(size 1.27 1.27)
				)
				(hide yes)
			)
		)
		(property "Description" ""
			(at 130.81 26.67 0)
			(effects
				(font
					(size 1.27 1.27)
				)
			)
		)
		(pin "1"
		)
		(instances
			(project "k410t-devboard"
				(path ""
					(reference "#PWR0505")
					(unit 1)
				)
			)
		)
	)
	(symbol
		(lib_id "antmicroCapacitors0402:C_100n_0402")
		(at 353.06 173.99 180)
		(unit 1)
		(exclude_from_sim no)
		(in_bom yes)
		(on_board yes)
		(dnp no)
		(property "Reference" "C303"
			(at 354.965 172.72 0)
			(effects
				(font
					(size 1.27 1.27)
				)
			)
		)
		(property "Value" "C_100n_0402"
			(at 332.74 163.83 0)
			(effects
				(font
					(size 1.27 1.27)
					(thickness 0.15)
				)
				(justify left bottom)
				(hide yes)
			)
		)
		(property "Footprint" "antmicro-footprints:C_0402_1005Metric"
			(at 332.74 161.29 0)
			(effects
				(font
					(size 1.27 1.27)
					(thickness 0.15)
				)
				(justify left bottom)
				(hide yes)
			)
		)
		(property "Datasheet" "https://www.murata.com/products/productdetail?partno=GRM155R61H104KE14%23"
			(at 332.74 158.75 0)
			(effects
				(font
					(size 1.27 1.27)
					(thickness 0.15)
				)
				(justify left bottom)
				(hide yes)
			)
		)
		(property "Description" ""
			(at 353.06 173.99 0)
			(effects
				(font
					(size 1.27 1.27)
				)
			)
		)
		(property "Manufacturer" "Murata"
			(at 332.74 153.67 0)
			(effects
				(font
					(size 1.27 1.27)
					(thickness 0.15)
				)
				(justify left bottom)
				(hide yes)
			)
		)
		(property "MPN" "GRM155R61H104KE14D"
			(at 332.74 156.21 0)
			(effects
				(font
					(size 1.27 1.27)
					(thickness 0.15)
				)
				(justify left bottom)
				(hide yes)
			)
		)
		(property "Val" "100n"
			(at 346.075 172.085 0)
			(effects
				(font
					(size 1.27 1.27)
					(thickness 0.15)
				)
			)
		)
		(property "License" "Apache-2.0"
			(at 332.74 151.13 0)
			(effects
				(font
					(size 1.27 1.27)
					(thickness 0.15)
				)
				(justify left bottom)
				(hide yes)
			)
		)
		(property "Author" "Antmicro"
			(at 332.74 148.59 0)
			(effects
				(font
					(size 1.27 1.27)
					(thickness 0.15)
				)
				(justify left bottom)
				(hide yes)
			)
		)
		(property "Voltage" "50V"
			(at 332.74 146.05 0)
			(effects
				(font
					(size 1.27 1.27)
				)
				(justify left bottom)
				(hide yes)
			)
		)
		(property "Dielectric" "X5R"
			(at 332.74 143.51 0)
			(effects
				(font
					(size 1.27 1.27)
				)
				(justify left bottom)
				(hide yes)
			)
		)
		(pin "1"
		)
		(pin "2"
		)
		(instances
			(project "k410t-devboard"
				(path ""
					(reference "C303")
					(unit 1)
				)
			)
		)
	)
	(symbol
		(lib_id "antmicropower:GND")
		(at 64.77 55.88 0)
		(unit 1)
		(exclude_from_sim no)
		(in_bom yes)
		(on_board yes)
		(dnp no)
		(fields_autoplaced yes)
		(property "Reference" "#PWR0357"
			(at 64.77 62.23 0)
			(effects
				(font
					(size 1.27 1.27)
				)
				(hide yes)
			)
		)
		(property "Value" "GND"
			(at 64.77 59.69 0)
			(effects
				(font
					(size 1.27 1.27)
				)
			)
		)
		(property "Footprint" ""
			(at 73.66 63.5 0)
			(effects
				(font
					(size 1.27 1.27)
					(thickness 0.15)
				)
				(justify left bottom)
				(hide yes)
			)
		)
		(property "Datasheet" ""
			(at 73.66 68.58 0)
			(effects
				(font
					(size 1.27 1.27)
					(thickness 0.15)
				)
				(justify left bottom)
				(hide yes)
			)
		)
		(property "Description" ""
			(at 64.77 55.88 0)
			(effects
				(font
					(size 1.27 1.27)
				)
			)
		)
		(property "Author" "Antmicro"
			(at 73.66 63.5 0)
			(effects
				(font
					(size 1.27 1.27)
					(thickness 0.15)
				)
				(justify left bottom)
				(hide yes)
			)
		)
		(property "License" "Apache-2.0"
			(at 73.66 66.04 0)
			(effects
				(font
					(size 1.27 1.27)
					(thickness 0.15)
				)
				(justify left bottom)
				(hide yes)
			)
		)
		(pin "1"
		)
		(instances
			(project "k410t-devboard"
				(path ""
					(reference "#PWR0357")
					(unit 1)
				)
			)
		)
	)
	(symbol
		(lib_id "antmicroResistors0402:R_33R_0402")
		(at 349.25 38.1 0)
		(unit 1)
		(exclude_from_sim no)
		(in_bom yes)
		(on_board yes)
		(dnp no)
		(property "Reference" "R270"
			(at 356.87 36.83 0)
			(effects
				(font
					(size 1.27 1.27)
				)
			)
		)
		(property "Value" "R_33R_0402"
			(at 369.57 50.8 0)
			(effects
				(font
					(size 1.27 1.27)
					(thickness 0.15)
				)
				(justify left bottom)
				(hide yes)
			)
		)
		(property "Footprint" "antmicro-footprints:R_0402_1005Metric"
			(at 369.57 53.34 0)
			(effects
				(font
					(size 1.27 1.27)
					(thickness 0.15)
				)
				(justify left bottom)
				(hide yes)
			)
		)
		(property "Datasheet" "https://www.bourns.com/docs/product-datasheets/cr.pdf"
			(at 369.57 55.88 0)
			(effects
				(font
					(size 1.27 1.27)
					(thickness 0.15)
				)
				(justify left bottom)
				(hide yes)
			)
		)
		(property "Description" ""
			(at 349.25 38.1 0)
			(effects
				(font
					(size 1.27 1.27)
				)
			)
		)
		(property "Manufacturer" "Bourns"
			(at 369.57 60.96 0)
			(effects
				(font
					(size 1.27 1.27)
					(thickness 0.15)
				)
				(justify left bottom)
				(hide yes)
			)
		)
		(property "MPN" "CR0402-FX-33R0GLF"
			(at 369.57 58.42 0)
			(effects
				(font
					(size 1.27 1.27)
					(thickness 0.15)
				)
				(justify left bottom)
				(hide yes)
			)
		)
		(property "Val" "33R"
			(at 347.345 36.83 0)
			(effects
				(font
					(size 1.27 1.27)
					(thickness 0.15)
				)
			)
		)
		(property "License" "Apache-2.0"
			(at 369.57 63.5 0)
			(effects
				(font
					(size 1.27 1.27)
					(thickness 0.15)
				)
				(justify left bottom)
				(hide yes)
			)
		)
		(property "Author" "Antmicro"
			(at 369.57 66.04 0)
			(effects
				(font
					(size 1.27 1.27)
					(thickness 0.15)
				)
				(justify left bottom)
				(hide yes)
			)
		)
		(property "Tolerance" "1%"
			(at 369.57 48.26 0)
			(effects
				(font
					(size 1.27 1.27)
				)
				(justify left bottom)
				(hide yes)
			)
		)
		(pin "1"
		)
		(pin "2"
		)
		(instances
			(project "k410t-devboard"
				(path ""
					(reference "R270")
					(unit 1)
				)
			)
		)
	)
	(symbol
		(lib_id "antmicroTestPoints:TP_0.75mm_SMD")
		(at 148.59 41.91 180)
		(unit 1)
		(exclude_from_sim no)
		(in_bom yes)
		(on_board yes)
		(dnp no)
		(property "Reference" "TP3"
			(at 142.875 41.91 0)
			(effects
				(font
					(size 1.27 1.27)
				)
			)
		)
		(property "Value" "TP_0.75mm_SMD"
			(at 133.35 34.29 0)
			(effects
				(font
					(size 1.27 1.27)
					(thickness 0.15)
				)
				(justify left bottom)
				(hide yes)
			)
		)
		(property "Footprint" "antmicro-footprints:TP_SMD_0.75mm"
			(at 133.35 31.75 0)
			(effects
				(font
					(size 1.27 1.27)
					(thickness 0.15)
				)
				(justify left bottom)
				(hide yes)
			)
		)
		(property "Datasheet" ""
			(at 133.35 29.21 0)
			(effects
				(font
					(size 1.27 1.27)
					(thickness 0.15)
				)
				(justify left bottom)
				(hide yes)
			)
		)
		(property "Description" ""
			(at 148.59 41.91 0)
			(effects
				(font
					(size 1.27 1.27)
				)
			)
		)
		(property "MPN" ""
			(at 148.59 41.91 0)
			(effects
				(font
					(size 1.27 1.27)
				)
				(hide yes)
			)
		)
		(property "Manufacturer" ""
			(at 148.59 41.91 0)
			(effects
				(font
					(size 1.27 1.27)
				)
				(hide yes)
			)
		)
		(property "Author" "Antmicro"
			(at 133.35 26.67 0)
			(effects
				(font
					(size 1.27 1.27)
					(thickness 0.15)
				)
				(justify left bottom)
				(hide yes)
			)
		)
		(property "License" "Apache-2.0"
			(at 133.35 24.13 0)
			(effects
				(font
					(size 1.27 1.27)
					(thickness 0.15)
				)
				(justify left bottom)
				(hide yes)
			)
		)
		(pin "1"
		)
		(instances
			(project "k410t-devboard"
				(path ""
					(reference "TP3")
					(unit 1)
				)
			)
		)
	)
	(symbol
		(lib_id "antmicroDiodesRectifiersSingle:PMEG3050EP,115")
		(at 29.21 34.29 270)
		(unit 1)
		(exclude_from_sim no)
		(in_bom no)
		(on_board yes)
		(dnp yes)
		(fields_autoplaced yes)
		(property "Reference" "D32"
			(at 31.75 34.6074 90)
			(effects
				(font
					(size 1.27 1.27)
				)
				(justify left)
			)
		)
		(property "Value" "PMEG3050EP,115"
			(at 31.75 37.1474 90)
			(effects
				(font
					(size 1.27 1.27)
					(thickness 0.15)
				)
				(justify left)
			)
		)
		(property "Footprint" "antmicro-footprints:Nexperia_SOD128"
			(at 19.05 55.88 0)
			(effects
				(font
					(size 1.27 1.27)
					(thickness 0.15)
				)
				(justify left bottom)
				(hide yes)
			)
		)
		(property "Datasheet" "https://www.mouser.com/datasheet/2/916/PMEG3050EP-2938519.pdf"
			(at 16.51 55.88 0)
			(effects
				(font
					(size 1.27 1.27)
					(thickness 0.15)
				)
				(justify left bottom)
				(hide yes)
			)
		)
		(property "Description" ""
			(at 29.21 34.29 0)
			(effects
				(font
					(size 1.27 1.27)
				)
			)
		)
		(property "MPN" "PMEG3050EP,115"
			(at 13.97 55.88 0)
			(effects
				(font
					(size 1.27 1.27)
					(thickness 0.15)
				)
				(justify left bottom)
				(hide yes)
			)
		)
		(property "Manufacturer" "Nexperia"
			(at 11.43 55.88 0)
			(effects
				(font
					(size 1.27 1.27)
					(thickness 0.15)
				)
				(justify left bottom)
				(hide yes)
			)
		)
		(property "DNP" "DNP"
			(at 31.75 39.6874 90)
			(effects
				(font
					(size 1.27 1.27)
				)
				(justify left)
			)
		)
		(property "Author" "Antmicro"
			(at 8.89 55.88 0)
			(effects
				(font
					(size 1.27 1.27)
					(thickness 0.15)
				)
				(justify left bottom)
				(hide yes)
			)
		)
		(property "License" "Apache-2.0"
			(at 6.35 55.88 0)
			(effects
				(font
					(size 1.27 1.27)
					(thickness 0.15)
				)
				(justify left bottom)
				(hide yes)
			)
		)
		(pin "1"
		)
		(pin "2"
		)
		(instances
			(project "k410t-devboard"
				(path ""
					(reference "D32")
					(unit 1)
				)
			)
		)
	)
	(symbol
		(lib_id "antmicroResistors0402:R_10k_0402")
		(at 139.7 35.56 90)
		(unit 1)
		(exclude_from_sim no)
		(in_bom yes)
		(on_board yes)
		(dnp no)
		(property "Reference" "R266"
			(at 140.97 31.75 90)
			(effects
				(font
					(size 1.27 1.27)
				)
				(justify right)
			)
		)
		(property "Value" "R_10k_0402"
			(at 152.4 15.24 0)
			(effects
				(font
					(size 1.27 1.27)
					(thickness 0.15)
				)
				(justify left bottom)
				(hide yes)
			)
		)
		(property "Footprint" "antmicro-footprints:R_0402_1005Metric"
			(at 154.94 15.24 0)
			(effects
				(font
					(size 1.27 1.27)
					(thickness 0.15)
				)
				(justify left bottom)
				(hide yes)
			)
		)
		(property "Datasheet" "https://www.bourns.com/docs/product-datasheets/cr.pdf"
			(at 157.48 15.24 0)
			(effects
				(font
					(size 1.27 1.27)
					(thickness 0.15)
				)
				(justify left bottom)
				(hide yes)
			)
		)
		(property "Description" ""
			(at 139.7 35.56 0)
			(effects
				(font
					(size 1.27 1.27)
				)
			)
		)
		(property "Manufacturer" "Bourns"
			(at 162.56 15.24 0)
			(effects
				(font
					(size 1.27 1.27)
					(thickness 0.15)
				)
				(justify left bottom)
				(hide yes)
			)
		)
		(property "MPN" "CR0402-FX-1002GLF"
			(at 160.02 15.24 0)
			(effects
				(font
					(size 1.27 1.27)
					(thickness 0.15)
				)
				(justify left bottom)
				(hide yes)
			)
		)
		(property "Val" "10k"
			(at 140.97 34.29 90)
			(effects
				(font
					(size 1.27 1.27)
					(thickness 0.15)
				)
				(justify right)
			)
		)
		(property "License" "Apache-2.0"
			(at 165.1 15.24 0)
			(effects
				(font
					(size 1.27 1.27)
					(thickness 0.15)
				)
				(justify left bottom)
				(hide yes)
			)
		)
		(property "Author" "Antmicro"
			(at 167.64 15.24 0)
			(effects
				(font
					(size 1.27 1.27)
					(thickness 0.15)
				)
				(justify left bottom)
				(hide yes)
			)
		)
		(property "Tolerance" "1%"
			(at 149.86 15.24 0)
			(effects
				(font
					(size 1.27 1.27)
				)
				(justify left bottom)
				(hide yes)
			)
		)
		(pin "1"
		)
		(pin "2"
		)
		(instances
			(project "k410t-devboard"
				(path ""
					(reference "R266")
					(unit 1)
				)
			)
		)
	)
	(symbol
		(lib_id "antmicroCapacitors0402:C_100n_0402")
		(at 29.21 53.34 90)
		(unit 1)
		(exclude_from_sim no)
		(in_bom yes)
		(on_board yes)
		(dnp no)
		(property "Reference" "C296"
			(at 34.925 48.895 90)
			(effects
				(font
					(size 1.27 1.27)
				)
				(justify left)
			)
		)
		(property "Value" "C_100n_0402"
			(at 39.37 33.02 0)
			(effects
				(font
					(size 1.27 1.27)
					(thickness 0.15)
				)
				(justify left bottom)
				(hide yes)
			)
		)
		(property "Footprint" "antmicro-footprints:C_0402_1005Metric"
			(at 41.91 33.02 0)
			(effects
				(font
					(size 1.27 1.27)
					(thickness 0.15)
				)
				(justify left bottom)
				(hide yes)
			)
		)
		(property "Datasheet" "https://www.murata.com/products/productdetail?partno=GRM155R61H104KE14%23"
			(at 44.45 33.02 0)
			(effects
				(font
					(size 1.27 1.27)
					(thickness 0.15)
				)
				(justify left bottom)
				(hide yes)
			)
		)
		(property "Description" ""
			(at 29.21 53.34 0)
			(effects
				(font
					(size 1.27 1.27)
				)
			)
		)
		(property "Manufacturer" "Murata"
			(at 49.53 33.02 0)
			(effects
				(font
					(size 1.27 1.27)
					(thickness 0.15)
				)
				(justify left bottom)
				(hide yes)
			)
		)
		(property "MPN" "GRM155R61H104KE14D"
			(at 46.99 33.02 0)
			(effects
				(font
					(size 1.27 1.27)
					(thickness 0.15)
				)
				(justify left bottom)
				(hide yes)
			)
		)
		(property "Val" "100n"
			(at 34.925 52.705 90)
			(effects
				(font
					(size 1.27 1.27)
					(thickness 0.15)
				)
				(justify left)
			)
		)
		(property "License" "Apache-2.0"
			(at 52.07 33.02 0)
			(effects
				(font
					(size 1.27 1.27)
					(thickness 0.15)
				)
				(justify left bottom)
				(hide yes)
			)
		)
		(property "Author" "Antmicro"
			(at 54.61 33.02 0)
			(effects
				(font
					(size 1.27 1.27)
					(thickness 0.15)
				)
				(justify left bottom)
				(hide yes)
			)
		)
		(property "Voltage" "50V"
			(at 57.15 33.02 0)
			(effects
				(font
					(size 1.27 1.27)
				)
				(justify left bottom)
				(hide yes)
			)
		)
		(property "Dielectric" "X5R"
			(at 59.69 33.02 0)
			(effects
				(font
					(size 1.27 1.27)
				)
				(justify left bottom)
				(hide yes)
			)
		)
		(pin "1"
		)
		(pin "2"
		)
		(instances
			(project "k410t-devboard"
				(path ""
					(reference "C296")
					(unit 1)
				)
			)
		)
	)
	(symbol
		(lib_id "antmicroResistors0402:R_100k_0402")
		(at 130.81 35.56 90)
		(unit 1)
		(exclude_from_sim no)
		(in_bom yes)
		(on_board yes)
		(dnp no)
		(property "Reference" "R264"
			(at 132.08 31.75 90)
			(effects
				(font
					(size 1.27 1.27)
				)
				(justify right)
			)
		)
		(property "Value" "R_100k_0402"
			(at 143.51 15.24 0)
			(effects
				(font
					(size 1.27 1.27)
					(thickness 0.15)
				)
				(justify left bottom)
				(hide yes)
			)
		)
		(property "Footprint" "antmicro-footprints:R_0402_1005Metric"
			(at 146.05 15.24 0)
			(effects
				(font
					(size 1.27 1.27)
					(thickness 0.15)
				)
				(justify left bottom)
				(hide yes)
			)
		)
		(property "Datasheet" "https://www.bourns.com/docs/product-datasheets/cr.pdf"
			(at 148.59 15.24 0)
			(effects
				(font
					(size 1.27 1.27)
					(thickness 0.15)
				)
				(justify left bottom)
				(hide yes)
			)
		)
		(property "Description" ""
			(at 130.81 35.56 0)
			(effects
				(font
					(size 1.27 1.27)
				)
			)
		)
		(property "Manufacturer" "Bourns"
			(at 153.67 15.24 0)
			(effects
				(font
					(size 1.27 1.27)
					(thickness 0.15)
				)
				(justify left bottom)
				(hide yes)
			)
		)
		(property "MPN" "CR0402-FX-1003GLF"
			(at 151.13 15.24 0)
			(effects
				(font
					(size 1.27 1.27)
					(thickness 0.15)
				)
				(justify left bottom)
				(hide yes)
			)
		)
		(property "Val" "100k"
			(at 132.08 34.29 90)
			(effects
				(font
					(size 1.27 1.27)
					(thickness 0.15)
				)
				(justify right)
			)
		)
		(property "License" "Apache-2.0"
			(at 156.21 15.24 0)
			(effects
				(font
					(size 1.27 1.27)
					(thickness 0.15)
				)
				(justify left bottom)
				(hide yes)
			)
		)
		(property "Author" "Antmicro"
			(at 158.75 15.24 0)
			(effects
				(font
					(size 1.27 1.27)
					(thickness 0.15)
				)
				(justify left bottom)
				(hide yes)
			)
		)
		(property "Tolerance" "1%"
			(at 140.97 15.24 0)
			(effects
				(font
					(size 1.27 1.27)
				)
				(justify left bottom)
				(hide yes)
			)
		)
		(pin "1"
		)
		(pin "2"
		)
		(instances
			(project "k410t-devboard"
				(path ""
					(reference "R264")
					(unit 1)
				)
			)
		)
	)
	(symbol
		(lib_id "antmicropower:+3.3V")
		(at 139.7 26.67 0)
		(unit 1)
		(exclude_from_sim no)
		(in_bom yes)
		(on_board yes)
		(dnp no)
		(property "Reference" "#PWR0347"
			(at 139.7 30.48 0)
			(effects
				(font
					(size 1.27 1.27)
				)
				(hide yes)
			)
		)
		(property "Value" "+3V3"
			(at 139.7 23.114 0)
			(effects
				(font
					(size 1.27 1.27)
				)
			)
		)
		(property "Footprint" ""
			(at 139.7 26.67 0)
			(effects
				(font
					(size 1.27 1.27)
				)
				(hide yes)
			)
		)
		(property "Datasheet" ""
			(at 139.7 26.67 0)
			(effects
				(font
					(size 1.27 1.27)
				)
				(hide yes)
			)
		)
		(property "Description" ""
			(at 139.7 26.67 0)
			(effects
				(font
					(size 1.27 1.27)
				)
			)
		)
		(pin "1"
		)
		(instances
			(project "k410t-devboard"
				(path ""
					(reference "#PWR0347")
					(unit 1)
				)
			)
		)
	)
	(symbol
		(lib_id "antmicroResistors0402:R_33R_0402")
		(at 349.25 67.31 0)
		(unit 1)
		(exclude_from_sim no)
		(in_bom yes)
		(on_board yes)
		(dnp no)
		(property "Reference" "R276"
			(at 356.87 66.04 0)
			(effects
				(font
					(size 1.27 1.27)
				)
			)
		)
		(property "Value" "R_33R_0402"
			(at 369.57 80.01 0)
			(effects
				(font
					(size 1.27 1.27)
					(thickness 0.15)
				)
				(justify left bottom)
				(hide yes)
			)
		)
		(property "Footprint" "antmicro-footprints:R_0402_1005Metric"
			(at 369.57 82.55 0)
			(effects
				(font
					(size 1.27 1.27)
					(thickness 0.15)
				)
				(justify left bottom)
				(hide yes)
			)
		)
		(property "Datasheet" "https://www.bourns.com/docs/product-datasheets/cr.pdf"
			(at 369.57 85.09 0)
			(effects
				(font
					(size 1.27 1.27)
					(thickness 0.15)
				)
				(justify left bottom)
				(hide yes)
			)
		)
		(property "Description" ""
			(at 349.25 67.31 0)
			(effects
				(font
					(size 1.27 1.27)
				)
			)
		)
		(property "Manufacturer" "Bourns"
			(at 369.57 90.17 0)
			(effects
				(font
					(size 1.27 1.27)
					(thickness 0.15)
				)
				(justify left bottom)
				(hide yes)
			)
		)
		(property "MPN" "CR0402-FX-33R0GLF"
			(at 369.57 87.63 0)
			(effects
				(font
					(size 1.27 1.27)
					(thickness 0.15)
				)
				(justify left bottom)
				(hide yes)
			)
		)
		(property "Val" "33R"
			(at 347.345 66.04 0)
			(effects
				(font
					(size 1.27 1.27)
					(thickness 0.15)
				)
			)
		)
		(property "License" "Apache-2.0"
			(at 369.57 92.71 0)
			(effects
				(font
					(size 1.27 1.27)
					(thickness 0.15)
				)
				(justify left bottom)
				(hide yes)
			)
		)
		(property "Author" "Antmicro"
			(at 369.57 95.25 0)
			(effects
				(font
					(size 1.27 1.27)
					(thickness 0.15)
				)
				(justify left bottom)
				(hide yes)
			)
		)
		(property "Tolerance" "1%"
			(at 369.57 77.47 0)
			(effects
				(font
					(size 1.27 1.27)
				)
				(justify left bottom)
				(hide yes)
			)
		)
		(pin "1"
		)
		(pin "2"
		)
		(instances
			(project "k410t-devboard"
				(path ""
					(reference "R276")
					(unit 1)
				)
			)
		)
	)
	(symbol
		(lib_id "antmicroCapacitors0402:C_100n_0402")
		(at 353.06 194.31 180)
		(unit 1)
		(exclude_from_sim no)
		(in_bom yes)
		(on_board yes)
		(dnp no)
		(property "Reference" "C307"
			(at 355.6 193.04 0)
			(effects
				(font
					(size 1.27 1.27)
				)
			)
		)
		(property "Value" "C_100n_0402"
			(at 332.74 184.15 0)
			(effects
				(font
					(size 1.27 1.27)
					(thickness 0.15)
				)
				(justify left bottom)
				(hide yes)
			)
		)
		(property "Footprint" "antmicro-footprints:C_0402_1005Metric"
			(at 332.74 181.61 0)
			(effects
				(font
					(size 1.27 1.27)
					(thickness 0.15)
				)
				(justify left bottom)
				(hide yes)
			)
		)
		(property "Datasheet" "https://www.murata.com/products/productdetail?partno=GRM155R61H104KE14%23"
			(at 332.74 179.07 0)
			(effects
				(font
					(size 1.27 1.27)
					(thickness 0.15)
				)
				(justify left bottom)
				(hide yes)
			)
		)
		(property "Description" ""
			(at 353.06 194.31 0)
			(effects
				(font
					(size 1.27 1.27)
				)
			)
		)
		(property "Manufacturer" "Murata"
			(at 332.74 173.99 0)
			(effects
				(font
					(size 1.27 1.27)
					(thickness 0.15)
				)
				(justify left bottom)
				(hide yes)
			)
		)
		(property "MPN" "GRM155R61H104KE14D"
			(at 332.74 176.53 0)
			(effects
				(font
					(size 1.27 1.27)
					(thickness 0.15)
				)
				(justify left bottom)
				(hide yes)
			)
		)
		(property "Val" "100n"
			(at 346.075 193.04 0)
			(effects
				(font
					(size 1.27 1.27)
					(thickness 0.15)
				)
			)
		)
		(property "License" "Apache-2.0"
			(at 332.74 171.45 0)
			(effects
				(font
					(size 1.27 1.27)
					(thickness 0.15)
				)
				(justify left bottom)
				(hide yes)
			)
		)
		(property "Author" "Antmicro"
			(at 332.74 168.91 0)
			(effects
				(font
					(size 1.27 1.27)
					(thickness 0.15)
				)
				(justify left bottom)
				(hide yes)
			)
		)
		(property "Voltage" "50V"
			(at 332.74 166.37 0)
			(effects
				(font
					(size 1.27 1.27)
				)
				(justify left bottom)
				(hide yes)
			)
		)
		(property "Dielectric" "X5R"
			(at 332.74 163.83 0)
			(effects
				(font
					(size 1.27 1.27)
				)
				(justify left bottom)
				(hide yes)
			)
		)
		(pin "1"
		)
		(pin "2"
		)
		(instances
			(project "k410t-devboard"
				(path ""
					(reference "C307")
					(unit 1)
				)
			)
		)
	)
	(symbol
		(lib_id "antmicroCapacitors0402:C_100n_0402")
		(at 353.06 163.83 180)
		(unit 1)
		(exclude_from_sim no)
		(in_bom yes)
		(on_board yes)
		(dnp no)
		(property "Reference" "C301"
			(at 354.965 162.56 0)
			(effects
				(font
					(size 1.27 1.27)
				)
			)
		)
		(property "Value" "C_100n_0402"
			(at 332.74 153.67 0)
			(effects
				(font
					(size 1.27 1.27)
					(thickness 0.15)
				)
				(justify left bottom)
				(hide yes)
			)
		)
		(property "Footprint" "antmicro-footprints:C_0402_1005Metric"
			(at 332.74 151.13 0)
			(effects
				(font
					(size 1.27 1.27)
					(thickness 0.15)
				)
				(justify left bottom)
				(hide yes)
			)
		)
		(property "Datasheet" "https://www.murata.com/products/productdetail?partno=GRM155R61H104KE14%23"
			(at 332.74 148.59 0)
			(effects
				(font
					(size 1.27 1.27)
					(thickness 0.15)
				)
				(justify left bottom)
				(hide yes)
			)
		)
		(property "Description" ""
			(at 353.06 163.83 0)
			(effects
				(font
					(size 1.27 1.27)
				)
			)
		)
		(property "Manufacturer" "Murata"
			(at 332.74 143.51 0)
			(effects
				(font
					(size 1.27 1.27)
					(thickness 0.15)
				)
				(justify left bottom)
				(hide yes)
			)
		)
		(property "MPN" "GRM155R61H104KE14D"
			(at 332.74 146.05 0)
			(effects
				(font
					(size 1.27 1.27)
					(thickness 0.15)
				)
				(justify left bottom)
				(hide yes)
			)
		)
		(property "Val" "100n"
			(at 346.075 161.925 0)
			(effects
				(font
					(size 1.27 1.27)
					(thickness 0.15)
				)
			)
		)
		(property "License" "Apache-2.0"
			(at 332.74 140.97 0)
			(effects
				(font
					(size 1.27 1.27)
					(thickness 0.15)
				)
				(justify left bottom)
				(hide yes)
			)
		)
		(property "Author" "Antmicro"
			(at 332.74 138.43 0)
			(effects
				(font
					(size 1.27 1.27)
					(thickness 0.15)
				)
				(justify left bottom)
				(hide yes)
			)
		)
		(property "Voltage" "50V"
			(at 332.74 135.89 0)
			(effects
				(font
					(size 1.27 1.27)
				)
				(justify left bottom)
				(hide yes)
			)
		)
		(property "Dielectric" "X5R"
			(at 332.74 133.35 0)
			(effects
				(font
					(size 1.27 1.27)
				)
				(justify left bottom)
				(hide yes)
			)
		)
		(pin "1"
		)
		(pin "2"
		)
		(instances
			(project "k410t-devboard"
				(path ""
					(reference "C301")
					(unit 1)
				)
			)
		)
	)
	(symbol
		(lib_id "antmicroResistors0402:R_33R_0402")
		(at 349.25 62.23 0)
		(unit 1)
		(exclude_from_sim no)
		(in_bom yes)
		(on_board yes)
		(dnp no)
		(property "Reference" "R275"
			(at 356.87 60.96 0)
			(effects
				(font
					(size 1.27 1.27)
				)
			)
		)
		(property "Value" "R_33R_0402"
			(at 369.57 74.93 0)
			(effects
				(font
					(size 1.27 1.27)
					(thickness 0.15)
				)
				(justify left bottom)
				(hide yes)
			)
		)
		(property "Footprint" "antmicro-footprints:R_0402_1005Metric"
			(at 369.57 77.47 0)
			(effects
				(font
					(size 1.27 1.27)
					(thickness 0.15)
				)
				(justify left bottom)
				(hide yes)
			)
		)
		(property "Datasheet" "https://www.bourns.com/docs/product-datasheets/cr.pdf"
			(at 369.57 80.01 0)
			(effects
				(font
					(size 1.27 1.27)
					(thickness 0.15)
				)
				(justify left bottom)
				(hide yes)
			)
		)
		(property "Description" ""
			(at 349.25 62.23 0)
			(effects
				(font
					(size 1.27 1.27)
				)
			)
		)
		(property "Manufacturer" "Bourns"
			(at 369.57 85.09 0)
			(effects
				(font
					(size 1.27 1.27)
					(thickness 0.15)
				)
				(justify left bottom)
				(hide yes)
			)
		)
		(property "MPN" "CR0402-FX-33R0GLF"
			(at 369.57 82.55 0)
			(effects
				(font
					(size 1.27 1.27)
					(thickness 0.15)
				)
				(justify left bottom)
				(hide yes)
			)
		)
		(property "Val" "33R"
			(at 347.345 60.96 0)
			(effects
				(font
					(size 1.27 1.27)
					(thickness 0.15)
				)
			)
		)
		(property "License" "Apache-2.0"
			(at 369.57 87.63 0)
			(effects
				(font
					(size 1.27 1.27)
					(thickness 0.15)
				)
				(justify left bottom)
				(hide yes)
			)
		)
		(property "Author" "Antmicro"
			(at 369.57 90.17 0)
			(effects
				(font
					(size 1.27 1.27)
					(thickness 0.15)
				)
				(justify left bottom)
				(hide yes)
			)
		)
		(property "Tolerance" "1%"
			(at 369.57 72.39 0)
			(effects
				(font
					(size 1.27 1.27)
				)
				(justify left bottom)
				(hide yes)
			)
		)
		(pin "1"
		)
		(pin "2"
		)
		(instances
			(project "k410t-devboard"
				(path ""
					(reference "R275")
					(unit 1)
				)
			)
		)
	)
	(symbol
		(lib_id "antmicroCapacitorsmisc:C_47u_16V_1206")
		(at 38.1 53.34 90)
		(unit 1)
		(exclude_from_sim no)
		(in_bom yes)
		(on_board yes)
		(dnp no)
		(property "Reference" "C297"
			(at 38.735 48.895 90)
			(effects
				(font
					(size 1.27 1.27)
				)
				(justify right)
			)
		)
		(property "Value" "C_47u_16V_1206"
			(at 48.26 33.02 0)
			(effects
				(font
					(size 1.27 1.27)
					(thickness 0.15)
				)
				(justify left bottom)
				(hide yes)
			)
		)
		(property "Footprint" "antmicro-footprints:C_1206_3216Metric"
			(at 50.8 33.02 0)
			(effects
				(font
					(size 1.27 1.27)
					(thickness 0.15)
				)
				(justify left bottom)
				(hide yes)
			)
		)
		(property "Datasheet" "https://product.tdk.com/en/search/capacitor/ceramic/mlcc/info?part_no=C3216X5R1C476M160AB"
			(at 53.34 33.02 0)
			(effects
				(font
					(size 1.27 1.27)
					(thickness 0.15)
				)
				(justify left bottom)
				(hide yes)
			)
		)
		(property "Description" ""
			(at 38.1 53.34 0)
			(effects
				(font
					(size 1.27 1.27)
				)
			)
		)
		(property "Manufacturer" "TDK"
			(at 58.42 33.02 0)
			(effects
				(font
					(size 1.27 1.27)
					(thickness 0.15)
				)
				(justify left bottom)
				(hide yes)
			)
		)
		(property "MPN" "C3216X5R1C476M160AB"
			(at 55.88 33.02 0)
			(effects
				(font
					(size 1.27 1.27)
					(thickness 0.15)
				)
				(justify left bottom)
				(hide yes)
			)
		)
		(property "Val" "47u"
			(at 38.735 52.705 90)
			(effects
				(font
					(size 1.27 1.27)
					(thickness 0.15)
				)
				(justify right)
			)
		)
		(property "License" "Apache-2.0"
			(at 60.96 33.02 0)
			(effects
				(font
					(size 1.27 1.27)
					(thickness 0.15)
				)
				(justify left bottom)
				(hide yes)
			)
		)
		(property "Author" "Antmicro"
			(at 63.5 33.02 0)
			(effects
				(font
					(size 1.27 1.27)
					(thickness 0.15)
				)
				(justify left bottom)
				(hide yes)
			)
		)
		(property "Voltage" "16V"
			(at 66.04 33.02 0)
			(effects
				(font
					(size 1.27 1.27)
				)
				(justify left bottom)
			)
		)
		(property "Dielectric" "X5R"
			(at 68.58 33.02 0)
			(effects
				(font
					(size 1.27 1.27)
				)
				(justify left bottom)
				(hide yes)
			)
		)
		(pin "1"
		)
		(pin "2"
		)
		(instances
			(project "k410t-devboard"
				(path ""
					(reference "C297")
					(unit 1)
				)
			)
		)
	)
	(symbol
		(lib_id "antmicroB2BConnectors:ASP-184329-01_CUSTOM_mounting_holes")
		(at 280.67 33.02 0)
		(unit 7)
		(exclude_from_sim no)
		(in_bom yes)
		(on_board yes)
		(dnp no)
		(fields_autoplaced yes)
		(property "Reference" "J18"
			(at 266.065 19.05 0)
			(effects
				(font
					(size 1.27 1.27)
					(thickness 0.15)
				)
			)
		)
		(property "Value" "ASP-184329-01_mounting_holes"
			(at 266.065 22.225 0)
			(effects
				(font
					(size 1.27 1.27)
					(thickness 0.15)
				)
				(hide yes)
			)
		)
		(property "Footprint" "antmicro-footprints:ASP-184329-01_mounting_holes"
			(at 326.39 44.45 0)
			(effects
				(font
					(size 1.27 1.27)
					(thickness 0.15)
				)
				(justify left bottom)
				(hide yes)
			)
		)
		(property "Datasheet" "https://www.mouser.com/datasheet/2/527/asp_184329_01_mkt-2854128.pdf"
			(at 326.39 46.99 0)
			(effects
				(font
					(size 1.27 1.27)
					(thickness 0.15)
				)
				(justify left bottom)
				(hide yes)
			)
		)
		(property "Description" ""
			(at 280.67 33.02 0)
			(effects
				(font
					(size 1.27 1.27)
				)
			)
		)
		(property "Manufacturer" "Samtec"
			(at 326.39 49.53 0)
			(effects
				(font
					(size 1.27 1.27)
					(thickness 0.15)
				)
				(justify left bottom)
				(hide yes)
			)
		)
		(property "MPN" "ASP-184329-01"
			(at 266.065 21.59 0)
			(effects
				(font
					(size 1.27 1.27)
					(thickness 0.15)
				)
			)
		)
		(property "Author" "Antmicro"
			(at 326.39 54.61 0)
			(effects
				(font
					(size 1.27 1.27)
					(thickness 0.15)
				)
				(justify left bottom)
				(hide yes)
			)
		)
		(property "License" "Apache-2.0"
			(at 326.39 57.15 0)
			(effects
				(font
					(size 1.27 1.27)
					(thickness 0.15)
				)
				(justify left bottom)
				(hide yes)
			)
		)
		(pin "B20"
		)
		(pin "B21"
		)
		(pin "D04"
		)
		(pin "D05"
		)
		(pin "L04"
		)
		(pin "L05"
		)
		(pin "L08"
		)
		(pin "L09"
		)
		(pin "L12"
		)
		(pin "L13"
		)
		(pin "L16"
		)
		(pin "L17"
		)
		(pin "L20"
		)
		(pin "L21"
		)
		(pin "L24"
		)
		(pin "L25"
		)
		(pin "L28"
		)
		(pin "L29"
		)
		(pin "Z20"
		)
		(pin "Z21"
		)
		(pin "A01"
		)
		(pin "A04"
		)
		(pin "A05"
		)
		(pin "A08"
		)
		(pin "A09"
		)
		(pin "A12"
		)
		(pin "A13"
		)
		(pin "A16"
		)
		(pin "A17"
		)
		(pin "A20"
		)
		(pin "A21"
		)
		(pin "A24"
		)
		(pin "A25"
		)
		(pin "A28"
		)
		(pin "A29"
		)
		(pin "A32"
		)
		(pin "A33"
		)
		(pin "A36"
		)
		(pin "A37"
		)
		(pin "A40"
		)
		(pin "B02"
		)
		(pin "B03"
		)
		(pin "B06"
		)
		(pin "B07"
		)
		(pin "B10"
		)
		(pin "B11"
		)
		(pin "B14"
		)
		(pin "B15"
		)
		(pin "B18"
		)
		(pin "B19"
		)
		(pin "B22"
		)
		(pin "B23"
		)
		(pin "B26"
		)
		(pin "B27"
		)
		(pin "B30"
		)
		(pin "B31"
		)
		(pin "B34"
		)
		(pin "B35"
		)
		(pin "B38"
		)
		(pin "B39"
		)
		(pin "B40"
		)
		(pin "C01"
		)
		(pin "C04"
		)
		(pin "C05"
		)
		(pin "C08"
		)
		(pin "C09"
		)
		(pin "C12"
		)
		(pin "C13"
		)
		(pin "C16"
		)
		(pin "C17"
		)
		(pin "C20"
		)
		(pin "C21"
		)
		(pin "C24"
		)
		(pin "C25"
		)
		(pin "C28"
		)
		(pin "C29"
		)
		(pin "C32"
		)
		(pin "C33"
		)
		(pin "C35"
		)
		(pin "C36"
		)
		(pin "C37"
		)
		(pin "C38"
		)
		(pin "C39"
		)
		(pin "C40"
		)
		(pin "D02"
		)
		(pin "D03"
		)
		(pin "D06"
		)
		(pin "D07"
		)
		(pin "D10"
		)
		(pin "D13"
		)
		(pin "D16"
		)
		(pin "D19"
		)
		(pin "D22"
		)
		(pin "D25"
		)
		(pin "D28"
		)
		(pin "D32"
		)
		(pin "D36"
		)
		(pin "D37"
		)
		(pin "D38"
		)
		(pin "D39"
		)
		(pin "D40"
		)
		(pin "E01"
		)
		(pin "E04"
		)
		(pin "E05"
		)
		(pin "E08"
		)
		(pin "E11"
		)
		(pin "E14"
		)
		(pin "E17"
		)
		(pin "E20"
		)
		(pin "E23"
		)
		(pin "E26"
		)
		(pin "E29"
		)
		(pin "E32"
		)
		(pin "E35"
		)
		(pin "E38"
		)
		(pin "E39"
		)
		(pin "E40"
		)
		(pin "F02"
		)
		(pin "F03"
		)
		(pin "F06"
		)
		(pin "F09"
		)
		(pin "F12"
		)
		(pin "F15"
		)
		(pin "F18"
		)
		(pin "F21"
		)
		(pin "F24"
		)
		(pin "F27"
		)
		(pin "F30"
		)
		(pin "F33"
		)
		(pin "F36"
		)
		(pin "F39"
		)
		(pin "F40"
		)
		(pin "G01"
		)
		(pin "G04"
		)
		(pin "G05"
		)
		(pin "G08"
		)
		(pin "G11"
		)
		(pin "G14"
		)
		(pin "G17"
		)
		(pin "G20"
		)
		(pin "G23"
		)
		(pin "G26"
		)
		(pin "G29"
		)
		(pin "G32"
		)
		(pin "G35"
		)
		(pin "G38"
		)
		(pin "G39"
		)
		(pin "G40"
		)
		(pin "H01"
		)
		(pin "Z34"
		)
		(pin "Z35"
		)
		(pin "Z38"
		)
		(pin "Z39"
		)
		(pin "Z40"
		)
		(pin "C30"
		)
		(pin "H03"
		)
		(pin "H06"
		)
		(pin "H09"
		)
		(pin "H12"
		)
		(pin "H15"
		)
		(pin "H18"
		)
		(pin "H21"
		)
		(pin "H24"
		)
		(pin "H27"
		)
		(pin "H30"
		)
		(pin "H33"
		)
		(pin "H36"
		)
		(pin "H39"
		)
		(pin "H40"
		)
		(pin "J01"
		)
		(pin "J04"
		)
		(pin "J05"
		)
		(pin "J08"
		)
		(pin "J11"
		)
		(pin "J14"
		)
		(pin "J17"
		)
		(pin "J20"
		)
		(pin "J23"
		)
		(pin "J26"
		)
		(pin "J29"
		)
		(pin "J32"
		)
		(pin "J35"
		)
		(pin "J38"
		)
		(pin "J39"
		)
		(pin "J40"
		)
		(pin "K01"
		)
		(pin "K02"
		)
		(pin "K03"
		)
		(pin "K06"
		)
		(pin "K09"
		)
		(pin "K12"
		)
		(pin "K15"
		)
		(pin "K18"
		)
		(pin "K21"
		)
		(pin "K24"
		)
		(pin "K27"
		)
		(pin "K30"
		)
		(pin "K33"
		)
		(pin "K36"
		)
		(pin "K39"
		)
		(pin "K40"
		)
		(pin "L01"
		)
		(pin "L02"
		)
		(pin "L03"
		)
		(pin "L06"
		)
		(pin "L07"
		)
		(pin "L10"
		)
		(pin "L11"
		)
		(pin "L14"
		)
		(pin "L15"
		)
		(pin "L18"
		)
		(pin "L19"
		)
		(pin "L22"
		)
		(pin "L23"
		)
		(pin "L26"
		)
		(pin "L27"
		)
		(pin "L30"
		)
		(pin "L31"
		)
		(pin "L32"
		)
		(pin "L33"
		)
		(pin "L34"
		)
		(pin "L35"
		)
		(pin "L36"
		)
		(pin "L37"
		)
		(pin "L38"
		)
		(pin "L39"
		)
		(pin "L40"
		)
		(pin "M01"
		)
		(pin "M04"
		)
		(pin "M05"
		)
		(pin "M08"
		)
		(pin "M09"
		)
		(pin "M12"
		)
		(pin "M13"
		)
		(pin "M16"
		)
		(pin "M17"
		)
		(pin "M20"
		)
		(pin "M21"
		)
		(pin "M24"
		)
		(pin "M25"
		)
		(pin "M28"
		)
		(pin "M29"
		)
		(pin "M32"
		)
		(pin "M33"
		)
		(pin "M36"
		)
		(pin "M37"
		)
		(pin "M40"
		)
		(pin "Y01"
		)
		(pin "Y04"
		)
		(pin "Y05"
		)
		(pin "Y08"
		)
		(pin "Y09"
		)
		(pin "Y12"
		)
		(pin "Y13"
		)
		(pin "Y16"
		)
		(pin "Y17"
		)
		(pin "Y20"
		)
		(pin "Y21"
		)
		(pin "Y24"
		)
		(pin "Y25"
		)
		(pin "Y28"
		)
		(pin "Y29"
		)
		(pin "Y32"
		)
		(pin "Y33"
		)
		(pin "Y36"
		)
		(pin "Y37"
		)
		(pin "Y40"
		)
		(pin "Z02"
		)
		(pin "Z03"
		)
		(pin "Z06"
		)
		(pin "Z07"
		)
		(pin "Z10"
		)
		(pin "Z11"
		)
		(pin "Z14"
		)
		(pin "Z15"
		)
		(pin "Z18"
		)
		(pin "Z19"
		)
		(pin "Z22"
		)
		(pin "Z23"
		)
		(pin "Z26"
		)
		(pin "Z27"
		)
		(pin "Z30"
		)
		(pin "Z31"
		)
		(pin "M19"
		)
		(pin "M22"
		)
		(pin "M23"
		)
		(pin "M26"
		)
		(pin "M27"
		)
		(pin "M30"
		)
		(pin "M31"
		)
		(pin "M34"
		)
		(pin "M35"
		)
		(pin "M38"
		)
		(pin "C31"
		)
		(pin "C34"
		)
		(pin "D01"
		)
		(pin "D29"
		)
		(pin "D30"
		)
		(pin "D31"
		)
		(pin "D33"
		)
		(pin "D34"
		)
		(pin "D35"
		)
		(pin "F01"
		)
		(pin "H02"
		)
		(pin "Z01"
		)
		(pin "C10"
		)
		(pin "C11"
		)
		(pin "C14"
		)
		(pin "C15"
		)
		(pin "C18"
		)
		(pin "C19"
		)
		(pin "C22"
		)
		(pin "C23"
		)
		(pin "C26"
		)
		(pin "C27"
		)
		(pin "D08"
		)
		(pin "D09"
		)
		(pin "D11"
		)
		(pin "D12"
		)
		(pin "D14"
		)
		(pin "D15"
		)
		(pin "D17"
		)
		(pin "D18"
		)
		(pin "D20"
		)
		(pin "D21"
		)
		(pin "D23"
		)
		(pin "D24"
		)
		(pin "D26"
		)
		(pin "D27"
		)
		(pin "G06"
		)
		(pin "G07"
		)
		(pin "G09"
		)
		(pin "G10"
		)
		(pin "G12"
		)
		(pin "G13"
		)
		(pin "G15"
		)
		(pin "G16"
		)
		(pin "G18"
		)
		(pin "G19"
		)
		(pin "G21"
		)
		(pin "G22"
		)
		(pin "G24"
		)
		(pin "G25"
		)
		(pin "G27"
		)
		(pin "G28"
		)
		(pin "G30"
		)
		(pin "G31"
		)
		(pin "G33"
		)
		(pin "G34"
		)
		(pin "G36"
		)
		(pin "G37"
		)
		(pin "H07"
		)
		(pin "H08"
		)
		(pin "H10"
		)
		(pin "H11"
		)
		(pin "H13"
		)
		(pin "H14"
		)
		(pin "H16"
		)
		(pin "H17"
		)
		(pin "H19"
		)
		(pin "H20"
		)
		(pin "H22"
		)
		(pin "H23"
		)
		(pin "H25"
		)
		(pin "H26"
		)
		(pin "H28"
		)
		(pin "H29"
		)
		(pin "H31"
		)
		(pin "H32"
		)
		(pin "H34"
		)
		(pin "H35"
		)
		(pin "H37"
		)
		(pin "H38"
		)
		(pin "E02"
		)
		(pin "E03"
		)
		(pin "E06"
		)
		(pin "E07"
		)
		(pin "E09"
		)
		(pin "E10"
		)
		(pin "E12"
		)
		(pin "E13"
		)
		(pin "E15"
		)
		(pin "E16"
		)
		(pin "E18"
		)
		(pin "E19"
		)
		(pin "F04"
		)
		(pin "F05"
		)
		(pin "F07"
		)
		(pin "F08"
		)
		(pin "F10"
		)
		(pin "F11"
		)
		(pin "F13"
		)
		(pin "F14"
		)
		(pin "F16"
		)
		(pin "F17"
		)
		(pin "F19"
		)
		(pin "F20"
		)
		(pin "J06"
		)
		(pin "J07"
		)
		(pin "J09"
		)
		(pin "J10"
		)
		(pin "J12"
		)
		(pin "J13"
		)
		(pin "J15"
		)
		(pin "J16"
		)
		(pin "J18"
		)
		(pin "J19"
		)
		(pin "J21"
		)
		(pin "J22"
		)
		(pin "K07"
		)
		(pin "K08"
		)
		(pin "K10"
		)
		(pin "K11"
		)
		(pin "K13"
		)
		(pin "K14"
		)
		(pin "K16"
		)
		(pin "K17"
		)
		(pin "K19"
		)
		(pin "K20"
		)
		(pin "K22"
		)
		(pin "K23"
		)
		(pin "E21"
		)
		(pin "E22"
		)
		(pin "E24"
		)
		(pin "E25"
		)
		(pin "E27"
		)
		(pin "E28"
		)
		(pin "E30"
		)
		(pin "E31"
		)
		(pin "E33"
		)
		(pin "E34"
		)
		(pin "E36"
		)
		(pin "E37"
		)
		(pin "F22"
		)
		(pin "F23"
		)
		(pin "F25"
		)
		(pin "F26"
		)
		(pin "F28"
		)
		(pin "F29"
		)
		(pin "F31"
		)
		(pin "F32"
		)
		(pin "F34"
		)
		(pin "F35"
		)
		(pin "F37"
		)
		(pin "F38"
		)
		(pin "J24"
		)
		(pin "J25"
		)
		(pin "J27"
		)
		(pin "J28"
		)
		(pin "J30"
		)
		(pin "J31"
		)
		(pin "J33"
		)
		(pin "J34"
		)
		(pin "J36"
		)
		(pin "J37"
		)
		(pin "K25"
		)
		(pin "K26"
		)
		(pin "K28"
		)
		(pin "K29"
		)
		(pin "K31"
		)
		(pin "K32"
		)
		(pin "K34"
		)
		(pin "K35"
		)
		(pin "K37"
		)
		(pin "K38"
		)
		(pin "B01"
		)
		(pin "G02"
		)
		(pin "G03"
		)
		(pin "H04"
		)
		(pin "H05"
		)
		(pin "J02"
		)
		(pin "J03"
		)
		(pin "K04"
		)
		(pin "K05"
		)
		(pin "A02"
		)
		(pin "A03"
		)
		(pin "A06"
		)
		(pin "A07"
		)
		(pin "A10"
		)
		(pin "A11"
		)
		(pin "A14"
		)
		(pin "A15"
		)
		(pin "A18"
		)
		(pin "A19"
		)
		(pin "A22"
		)
		(pin "A23"
		)
		(pin "A26"
		)
		(pin "A27"
		)
		(pin "A30"
		)
		(pin "A31"
		)
		(pin "A34"
		)
		(pin "A35"
		)
		(pin "A38"
		)
		(pin "A39"
		)
		(pin "B04"
		)
		(pin "B05"
		)
		(pin "B08"
		)
		(pin "B09"
		)
		(pin "B12"
		)
		(pin "B13"
		)
		(pin "B16"
		)
		(pin "B17"
		)
		(pin "B24"
		)
		(pin "B25"
		)
		(pin "B28"
		)
		(pin "B29"
		)
		(pin "B32"
		)
		(pin "B33"
		)
		(pin "B36"
		)
		(pin "B37"
		)
		(pin "C02"
		)
		(pin "C03"
		)
		(pin "C06"
		)
		(pin "C07"
		)
		(pin "M02"
		)
		(pin "M03"
		)
		(pin "M06"
		)
		(pin "M07"
		)
		(pin "M10"
		)
		(pin "M11"
		)
		(pin "M14"
		)
		(pin "M15"
		)
		(pin "M18"
		)
		(pin "M39"
		)
		(pin "Y02"
		)
		(pin "Y03"
		)
		(pin "Y06"
		)
		(pin "Y07"
		)
		(pin "Y10"
		)
		(pin "Y11"
		)
		(pin "Y14"
		)
		(pin "Y15"
		)
		(pin "Y18"
		)
		(pin "Y19"
		)
		(pin "Y22"
		)
		(pin "Y23"
		)
		(pin "Y26"
		)
		(pin "Y27"
		)
		(pin "Y30"
		)
		(pin "Y31"
		)
		(pin "Y34"
		)
		(pin "Y35"
		)
		(pin "Y38"
		)
		(pin "Y39"
		)
		(pin "Z04"
		)
		(pin "Z05"
		)
		(pin "Z08"
		)
		(pin "Z09"
		)
		(pin "Z12"
		)
		(pin "Z13"
		)
		(pin "Z16"
		)
		(pin "Z17"
		)
		(pin "Z24"
		)
		(pin "Z25"
		)
		(pin "Z28"
		)
		(pin "Z29"
		)
		(pin "Z32"
		)
		(pin "Z33"
		)
		(pin "Z36"
		)
		(pin "Z37"
		)
		(instances
			(project "k410t-devboard"
				(path ""
					(reference "J18")
					(unit 7)
				)
			)
		)
	)
	(symbol
		(lib_id "antmicroResistors0402:R_4k7_0402")
		(at 213.36 46.99 270)
		(unit 1)
		(exclude_from_sim no)
		(in_bom yes)
		(on_board yes)
		(dnp no)
		(property "Reference" "R267"
			(at 214.63 48.26 90)
			(effects
				(font
					(size 1.27 1.27)
				)
				(justify left)
			)
		)
		(property "Value" "R_4k7_0402"
			(at 200.66 67.31 0)
			(effects
				(font
					(size 1.27 1.27)
					(thickness 0.15)
				)
				(justify left bottom)
				(hide yes)
			)
		)
		(property "Footprint" "antmicro-footprints:R_0402_1005Metric"
			(at 198.12 67.31 0)
			(effects
				(font
					(size 1.27 1.27)
					(thickness 0.15)
				)
				(justify left bottom)
				(hide yes)
			)
		)
		(property "Datasheet" "https://www.bourns.com/docs/product-datasheets/cr.pdf"
			(at 195.58 67.31 0)
			(effects
				(font
					(size 1.27 1.27)
					(thickness 0.15)
				)
				(justify left bottom)
				(hide yes)
			)
		)
		(property "Description" ""
			(at 213.36 46.99 0)
			(effects
				(font
					(size 1.27 1.27)
				)
			)
		)
		(property "Manufacturer" "Bourns"
			(at 190.5 67.31 0)
			(effects
				(font
					(size 1.27 1.27)
					(thickness 0.15)
				)
				(justify left bottom)
				(hide yes)
			)
		)
		(property "MPN" "CR0402-FX-4701GLF"
			(at 193.04 67.31 0)
			(effects
				(font
					(size 1.27 1.27)
					(thickness 0.15)
				)
				(justify left bottom)
				(hide yes)
			)
		)
		(property "Val" "4k7"
			(at 214.63 50.8 90)
			(effects
				(font
					(size 1.27 1.27)
					(thickness 0.15)
				)
				(justify left)
			)
		)
		(property "License" "Apache-2.0"
			(at 187.96 67.31 0)
			(effects
				(font
					(size 1.27 1.27)
					(thickness 0.15)
				)
				(justify left bottom)
				(hide yes)
			)
		)
		(property "Author" "Antmicro"
			(at 185.42 67.31 0)
			(effects
				(font
					(size 1.27 1.27)
					(thickness 0.15)
				)
				(justify left bottom)
				(hide yes)
			)
		)
		(property "Tolerance" "1%"
			(at 203.2 67.31 0)
			(effects
				(font
					(size 1.27 1.27)
				)
				(justify left bottom)
				(hide yes)
			)
		)
		(pin "1"
		)
		(pin "2"
		)
		(instances
			(project "k410t-devboard"
				(path ""
					(reference "R267")
					(unit 1)
				)
			)
		)
	)
	(symbol
		(lib_id "antmicroCapacitors0402:C_100n_0402")
		(at 353.06 158.75 180)
		(unit 1)
		(exclude_from_sim no)
		(in_bom yes)
		(on_board yes)
		(dnp no)
		(property "Reference" "C300"
			(at 354.965 157.48 0)
			(effects
				(font
					(size 1.27 1.27)
				)
			)
		)
		(property "Value" "C_100n_0402"
			(at 332.74 148.59 0)
			(effects
				(font
					(size 1.27 1.27)
					(thickness 0.15)
				)
				(justify left bottom)
				(hide yes)
			)
		)
		(property "Footprint" "antmicro-footprints:C_0402_1005Metric"
			(at 332.74 146.05 0)
			(effects
				(font
					(size 1.27 1.27)
					(thickness 0.15)
				)
				(justify left bottom)
				(hide yes)
			)
		)
		(property "Datasheet" "https://www.murata.com/products/productdetail?partno=GRM155R61H104KE14%23"
			(at 332.74 143.51 0)
			(effects
				(font
					(size 1.27 1.27)
					(thickness 0.15)
				)
				(justify left bottom)
				(hide yes)
			)
		)
		(property "Description" ""
			(at 353.06 158.75 0)
			(effects
				(font
					(size 1.27 1.27)
				)
			)
		)
		(property "Manufacturer" "Murata"
			(at 332.74 138.43 0)
			(effects
				(font
					(size 1.27 1.27)
					(thickness 0.15)
				)
				(justify left bottom)
				(hide yes)
			)
		)
		(property "MPN" "GRM155R61H104KE14D"
			(at 332.74 140.97 0)
			(effects
				(font
					(size 1.27 1.27)
					(thickness 0.15)
				)
				(justify left bottom)
				(hide yes)
			)
		)
		(property "Val" "100n"
			(at 346.075 156.845 0)
			(effects
				(font
					(size 1.27 1.27)
					(thickness 0.15)
				)
			)
		)
		(property "License" "Apache-2.0"
			(at 332.74 135.89 0)
			(effects
				(font
					(size 1.27 1.27)
					(thickness 0.15)
				)
				(justify left bottom)
				(hide yes)
			)
		)
		(property "Author" "Antmicro"
			(at 332.74 133.35 0)
			(effects
				(font
					(size 1.27 1.27)
					(thickness 0.15)
				)
				(justify left bottom)
				(hide yes)
			)
		)
		(property "Voltage" "50V"
			(at 332.74 130.81 0)
			(effects
				(font
					(size 1.27 1.27)
				)
				(justify left bottom)
				(hide yes)
			)
		)
		(property "Dielectric" "X5R"
			(at 332.74 128.27 0)
			(effects
				(font
					(size 1.27 1.27)
				)
				(justify left bottom)
				(hide yes)
			)
		)
		(pin "1"
		)
		(pin "2"
		)
		(instances
			(project "k410t-devboard"
				(path ""
					(reference "C300")
					(unit 1)
				)
			)
		)
	)
	(symbol
		(lib_id "antmicropower:GND")
		(at 29.21 57.15 0)
		(unit 1)
		(exclude_from_sim no)
		(in_bom yes)
		(on_board yes)
		(dnp no)
		(property "Reference" "#PWR0349"
			(at 29.21 63.5 0)
			(effects
				(font
					(size 1.27 1.27)
				)
				(hide yes)
			)
		)
		(property "Value" "GND"
			(at 29.21 60.96 0)
			(effects
				(font
					(size 1.27 1.27)
				)
			)
		)
		(property "Footprint" ""
			(at 38.1 64.77 0)
			(effects
				(font
					(size 1.27 1.27)
					(thickness 0.15)
				)
				(justify left bottom)
				(hide yes)
			)
		)
		(property "Datasheet" ""
			(at 38.1 69.85 0)
			(effects
				(font
					(size 1.27 1.27)
					(thickness 0.15)
				)
				(justify left bottom)
				(hide yes)
			)
		)
		(property "Description" ""
			(at 29.21 57.15 0)
			(effects
				(font
					(size 1.27 1.27)
				)
			)
		)
		(property "Author" "Antmicro"
			(at 38.1 64.77 0)
			(effects
				(font
					(size 1.27 1.27)
					(thickness 0.15)
				)
				(justify left bottom)
				(hide yes)
			)
		)
		(property "License" "Apache-2.0"
			(at 38.1 67.31 0)
			(effects
				(font
					(size 1.27 1.27)
					(thickness 0.15)
				)
				(justify left bottom)
				(hide yes)
			)
		)
		(pin "1"
		)
		(instances
			(project "k410t-devboard"
				(path ""
					(reference "#PWR0349")
					(unit 1)
				)
			)
		)
	)
	(symbol
		(lib_id "antmicroCapacitors0402:C_100n_0402")
		(at 353.06 168.91 180)
		(unit 1)
		(exclude_from_sim no)
		(in_bom yes)
		(on_board yes)
		(dnp no)
		(property "Reference" "C302"
			(at 354.965 167.64 0)
			(effects
				(font
					(size 1.27 1.27)
				)
			)
		)
		(property "Value" "C_100n_0402"
			(at 332.74 158.75 0)
			(effects
				(font
					(size 1.27 1.27)
					(thickness 0.15)
				)
				(justify left bottom)
				(hide yes)
			)
		)
		(property "Footprint" "antmicro-footprints:C_0402_1005Metric"
			(at 332.74 156.21 0)
			(effects
				(font
					(size 1.27 1.27)
					(thickness 0.15)
				)
				(justify left bottom)
				(hide yes)
			)
		)
		(property "Datasheet" "https://www.murata.com/products/productdetail?partno=GRM155R61H104KE14%23"
			(at 332.74 153.67 0)
			(effects
				(font
					(size 1.27 1.27)
					(thickness 0.15)
				)
				(justify left bottom)
				(hide yes)
			)
		)
		(property "Description" ""
			(at 353.06 168.91 0)
			(effects
				(font
					(size 1.27 1.27)
				)
			)
		)
		(property "Manufacturer" "Murata"
			(at 332.74 148.59 0)
			(effects
				(font
					(size 1.27 1.27)
					(thickness 0.15)
				)
				(justify left bottom)
				(hide yes)
			)
		)
		(property "MPN" "GRM155R61H104KE14D"
			(at 332.74 151.13 0)
			(effects
				(font
					(size 1.27 1.27)
					(thickness 0.15)
				)
				(justify left bottom)
				(hide yes)
			)
		)
		(property "Val" "100n"
			(at 346.075 167.005 0)
			(effects
				(font
					(size 1.27 1.27)
					(thickness 0.15)
				)
			)
		)
		(property "License" "Apache-2.0"
			(at 332.74 146.05 0)
			(effects
				(font
					(size 1.27 1.27)
					(thickness 0.15)
				)
				(justify left bottom)
				(hide yes)
			)
		)
		(property "Author" "Antmicro"
			(at 332.74 143.51 0)
			(effects
				(font
					(size 1.27 1.27)
					(thickness 0.15)
				)
				(justify left bottom)
				(hide yes)
			)
		)
		(property "Voltage" "50V"
			(at 332.74 140.97 0)
			(effects
				(font
					(size 1.27 1.27)
				)
				(justify left bottom)
				(hide yes)
			)
		)
		(property "Dielectric" "X5R"
			(at 332.74 138.43 0)
			(effects
				(font
					(size 1.27 1.27)
				)
				(justify left bottom)
				(hide yes)
			)
		)
		(pin "1"
		)
		(pin "2"
		)
		(instances
			(project "k410t-devboard"
				(path ""
					(reference "C302")
					(unit 1)
				)
			)
		)
	)
	(symbol
		(lib_id "antmicroB2BConnectors:ASP-184329-01_CUSTOM_mounting_holes")
		(at 60.96 97.79 0)
		(unit 5)
		(exclude_from_sim no)
		(in_bom yes)
		(on_board yes)
		(dnp no)
		(fields_autoplaced yes)
		(property "Reference" "J18"
			(at 77.47 83.82 0)
			(effects
				(font
					(size 1.27 1.27)
					(thickness 0.15)
				)
			)
		)
		(property "Value" "ASP-184329-01_mounting_holes"
			(at 77.47 87.63 0)
			(effects
				(font
					(size 1.27 1.27)
					(thickness 0.15)
				)
				(hide yes)
			)
		)
		(property "Footprint" "antmicro-footprints:ASP-184329-01_mounting_holes"
			(at 106.68 109.22 0)
			(effects
				(font
					(size 1.27 1.27)
					(thickness 0.15)
				)
				(justify left bottom)
				(hide yes)
			)
		)
		(property "Datasheet" "https://www.mouser.com/datasheet/2/527/asp_184329_01_mkt-2854128.pdf"
			(at 106.68 111.76 0)
			(effects
				(font
					(size 1.27 1.27)
					(thickness 0.15)
				)
				(justify left bottom)
				(hide yes)
			)
		)
		(property "Description" ""
			(at 60.96 97.79 0)
			(effects
				(font
					(size 1.27 1.27)
				)
			)
		)
		(property "Manufacturer" "Samtec"
			(at 106.68 114.3 0)
			(effects
				(font
					(size 1.27 1.27)
					(thickness 0.15)
				)
				(justify left bottom)
				(hide yes)
			)
		)
		(property "MPN" "ASP-184329-01"
			(at 77.47 86.36 0)
			(effects
				(font
					(size 1.27 1.27)
					(thickness 0.15)
				)
			)
		)
		(property "Author" "Antmicro"
			(at 106.68 119.38 0)
			(effects
				(font
					(size 1.27 1.27)
					(thickness 0.15)
				)
				(justify left bottom)
				(hide yes)
			)
		)
		(property "License" "Apache-2.0"
			(at 106.68 121.92 0)
			(effects
				(font
					(size 1.27 1.27)
					(thickness 0.15)
				)
				(justify left bottom)
				(hide yes)
			)
		)
		(pin "E21"
		)
		(pin "E22"
		)
		(pin "E24"
		)
		(pin "E25"
		)
		(pin "E27"
		)
		(pin "E28"
		)
		(pin "E30"
		)
		(pin "E31"
		)
		(pin "E33"
		)
		(pin "E34"
		)
		(pin "E36"
		)
		(pin "E37"
		)
		(pin "F22"
		)
		(pin "F23"
		)
		(pin "F25"
		)
		(pin "F26"
		)
		(pin "F28"
		)
		(pin "F29"
		)
		(pin "F31"
		)
		(pin "F32"
		)
		(pin "F34"
		)
		(pin "F35"
		)
		(pin "F37"
		)
		(pin "F38"
		)
		(pin "J24"
		)
		(pin "J25"
		)
		(pin "J27"
		)
		(pin "J28"
		)
		(pin "J30"
		)
		(pin "J31"
		)
		(pin "J33"
		)
		(pin "J34"
		)
		(pin "J36"
		)
		(pin "J37"
		)
		(pin "K25"
		)
		(pin "K26"
		)
		(pin "K28"
		)
		(pin "K29"
		)
		(pin "K31"
		)
		(pin "K32"
		)
		(pin "K34"
		)
		(pin "K35"
		)
		(pin "K37"
		)
		(pin "K38"
		)
		(pin "A04"
		)
		(pin "A05"
		)
		(pin "A01"
		)
		(pin "A08"
		)
		(pin "A09"
		)
		(pin "A12"
		)
		(pin "A13"
		)
		(pin "A16"
		)
		(pin "A17"
		)
		(pin "A20"
		)
		(pin "A21"
		)
		(pin "A24"
		)
		(pin "A25"
		)
		(pin "A28"
		)
		(pin "A29"
		)
		(pin "A32"
		)
		(pin "A33"
		)
		(pin "A36"
		)
		(pin "A37"
		)
		(pin "A40"
		)
		(pin "B02"
		)
		(pin "B03"
		)
		(pin "B06"
		)
		(pin "B07"
		)
		(pin "B10"
		)
		(pin "B11"
		)
		(pin "B14"
		)
		(pin "B15"
		)
		(pin "B18"
		)
		(pin "B19"
		)
		(pin "B22"
		)
		(pin "B23"
		)
		(pin "B26"
		)
		(pin "B27"
		)
		(pin "B30"
		)
		(pin "B31"
		)
		(pin "B34"
		)
		(pin "B35"
		)
		(pin "B38"
		)
		(pin "B39"
		)
		(pin "B40"
		)
		(pin "C01"
		)
		(pin "C04"
		)
		(pin "C05"
		)
		(pin "C08"
		)
		(pin "C09"
		)
		(pin "C12"
		)
		(pin "C13"
		)
		(pin "C16"
		)
		(pin "C17"
		)
		(pin "C20"
		)
		(pin "C21"
		)
		(pin "C24"
		)
		(pin "C25"
		)
		(pin "C28"
		)
		(pin "C29"
		)
		(pin "C32"
		)
		(pin "C33"
		)
		(pin "C35"
		)
		(pin "C36"
		)
		(pin "C37"
		)
		(pin "C38"
		)
		(pin "C39"
		)
		(pin "C40"
		)
		(pin "D02"
		)
		(pin "D03"
		)
		(pin "D06"
		)
		(pin "D07"
		)
		(pin "D10"
		)
		(pin "D13"
		)
		(pin "D16"
		)
		(pin "D19"
		)
		(pin "D22"
		)
		(pin "D25"
		)
		(pin "D28"
		)
		(pin "D32"
		)
		(pin "D36"
		)
		(pin "D37"
		)
		(pin "D38"
		)
		(pin "D39"
		)
		(pin "D40"
		)
		(pin "E01"
		)
		(pin "E04"
		)
		(pin "E05"
		)
		(pin "E08"
		)
		(pin "E11"
		)
		(pin "E14"
		)
		(pin "E17"
		)
		(pin "E20"
		)
		(pin "E23"
		)
		(pin "E26"
		)
		(pin "E29"
		)
		(pin "E32"
		)
		(pin "E35"
		)
		(pin "E38"
		)
		(pin "E39"
		)
		(pin "E40"
		)
		(pin "F02"
		)
		(pin "F03"
		)
		(pin "F06"
		)
		(pin "F09"
		)
		(pin "F12"
		)
		(pin "F15"
		)
		(pin "F18"
		)
		(pin "F21"
		)
		(pin "F24"
		)
		(pin "F27"
		)
		(pin "F30"
		)
		(pin "F33"
		)
		(pin "F36"
		)
		(pin "F39"
		)
		(pin "F40"
		)
		(pin "G01"
		)
		(pin "G04"
		)
		(pin "G05"
		)
		(pin "G08"
		)
		(pin "G11"
		)
		(pin "G14"
		)
		(pin "G17"
		)
		(pin "G20"
		)
		(pin "G23"
		)
		(pin "G26"
		)
		(pin "G29"
		)
		(pin "G32"
		)
		(pin "G35"
		)
		(pin "G38"
		)
		(pin "G39"
		)
		(pin "G40"
		)
		(pin "H01"
		)
		(pin "Z34"
		)
		(pin "Z35"
		)
		(pin "Z38"
		)
		(pin "Z39"
		)
		(pin "Z40"
		)
		(pin "C30"
		)
		(pin "H03"
		)
		(pin "H06"
		)
		(pin "H09"
		)
		(pin "H12"
		)
		(pin "H15"
		)
		(pin "H18"
		)
		(pin "H21"
		)
		(pin "H24"
		)
		(pin "H27"
		)
		(pin "H30"
		)
		(pin "H33"
		)
		(pin "H36"
		)
		(pin "H39"
		)
		(pin "H40"
		)
		(pin "J01"
		)
		(pin "J04"
		)
		(pin "J05"
		)
		(pin "J08"
		)
		(pin "J11"
		)
		(pin "J14"
		)
		(pin "J17"
		)
		(pin "J20"
		)
		(pin "J23"
		)
		(pin "J26"
		)
		(pin "J29"
		)
		(pin "J32"
		)
		(pin "J35"
		)
		(pin "J38"
		)
		(pin "J39"
		)
		(pin "J40"
		)
		(pin "K01"
		)
		(pin "K02"
		)
		(pin "K03"
		)
		(pin "K06"
		)
		(pin "K09"
		)
		(pin "K12"
		)
		(pin "K15"
		)
		(pin "K18"
		)
		(pin "K21"
		)
		(pin "K24"
		)
		(pin "K27"
		)
		(pin "K30"
		)
		(pin "K33"
		)
		(pin "K36"
		)
		(pin "K39"
		)
		(pin "K40"
		)
		(pin "L01"
		)
		(pin "L02"
		)
		(pin "L03"
		)
		(pin "L06"
		)
		(pin "L07"
		)
		(pin "L10"
		)
		(pin "L11"
		)
		(pin "L14"
		)
		(pin "L15"
		)
		(pin "L18"
		)
		(pin "L19"
		)
		(pin "L22"
		)
		(pin "L23"
		)
		(pin "L26"
		)
		(pin "L27"
		)
		(pin "L30"
		)
		(pin "L31"
		)
		(pin "L32"
		)
		(pin "L33"
		)
		(pin "L34"
		)
		(pin "L35"
		)
		(pin "L36"
		)
		(pin "L37"
		)
		(pin "L38"
		)
		(pin "L39"
		)
		(pin "L40"
		)
		(pin "M01"
		)
		(pin "M04"
		)
		(pin "M05"
		)
		(pin "M08"
		)
		(pin "M09"
		)
		(pin "M12"
		)
		(pin "M13"
		)
		(pin "M16"
		)
		(pin "M17"
		)
		(pin "M20"
		)
		(pin "M21"
		)
		(pin "M24"
		)
		(pin "M25"
		)
		(pin "M28"
		)
		(pin "M29"
		)
		(pin "M32"
		)
		(pin "M33"
		)
		(pin "M36"
		)
		(pin "M37"
		)
		(pin "M40"
		)
		(pin "Y01"
		)
		(pin "Y04"
		)
		(pin "Y05"
		)
		(pin "Y08"
		)
		(pin "Y09"
		)
		(pin "Y12"
		)
		(pin "Y13"
		)
		(pin "Y16"
		)
		(pin "Y17"
		)
		(pin "Y20"
		)
		(pin "Y21"
		)
		(pin "Y24"
		)
		(pin "Y25"
		)
		(pin "Y28"
		)
		(pin "Y29"
		)
		(pin "Y32"
		)
		(pin "Y33"
		)
		(pin "Y36"
		)
		(pin "Y37"
		)
		(pin "Y40"
		)
		(pin "Z02"
		)
		(pin "Z03"
		)
		(pin "Z06"
		)
		(pin "Z07"
		)
		(pin "Z10"
		)
		(pin "Z11"
		)
		(pin "Z14"
		)
		(pin "Z15"
		)
		(pin "Z18"
		)
		(pin "Z19"
		)
		(pin "Z22"
		)
		(pin "Z23"
		)
		(pin "Z26"
		)
		(pin "Z27"
		)
		(pin "Z30"
		)
		(pin "Z31"
		)
		(pin "M19"
		)
		(pin "M22"
		)
		(pin "M23"
		)
		(pin "M26"
		)
		(pin "M27"
		)
		(pin "M30"
		)
		(pin "M31"
		)
		(pin "M34"
		)
		(pin "M35"
		)
		(pin "M38"
		)
		(pin "C31"
		)
		(pin "C34"
		)
		(pin "D01"
		)
		(pin "D29"
		)
		(pin "D30"
		)
		(pin "D31"
		)
		(pin "D33"
		)
		(pin "D34"
		)
		(pin "D35"
		)
		(pin "F01"
		)
		(pin "H02"
		)
		(pin "Z01"
		)
		(pin "C10"
		)
		(pin "C11"
		)
		(pin "C14"
		)
		(pin "C15"
		)
		(pin "C18"
		)
		(pin "C19"
		)
		(pin "C22"
		)
		(pin "C23"
		)
		(pin "C26"
		)
		(pin "C27"
		)
		(pin "D08"
		)
		(pin "D09"
		)
		(pin "D11"
		)
		(pin "D12"
		)
		(pin "D14"
		)
		(pin "D15"
		)
		(pin "D17"
		)
		(pin "D18"
		)
		(pin "D20"
		)
		(pin "D21"
		)
		(pin "D23"
		)
		(pin "D24"
		)
		(pin "D26"
		)
		(pin "D27"
		)
		(pin "G06"
		)
		(pin "G07"
		)
		(pin "G09"
		)
		(pin "G10"
		)
		(pin "G12"
		)
		(pin "G13"
		)
		(pin "G15"
		)
		(pin "G16"
		)
		(pin "G18"
		)
		(pin "G19"
		)
		(pin "G21"
		)
		(pin "G22"
		)
		(pin "G24"
		)
		(pin "G25"
		)
		(pin "G27"
		)
		(pin "G28"
		)
		(pin "G30"
		)
		(pin "G31"
		)
		(pin "G33"
		)
		(pin "G34"
		)
		(pin "G36"
		)
		(pin "G37"
		)
		(pin "H07"
		)
		(pin "H08"
		)
		(pin "H10"
		)
		(pin "H11"
		)
		(pin "H13"
		)
		(pin "H14"
		)
		(pin "H16"
		)
		(pin "H17"
		)
		(pin "H19"
		)
		(pin "H20"
		)
		(pin "H22"
		)
		(pin "H23"
		)
		(pin "H25"
		)
		(pin "H26"
		)
		(pin "H28"
		)
		(pin "H29"
		)
		(pin "H31"
		)
		(pin "H32"
		)
		(pin "H34"
		)
		(pin "H35"
		)
		(pin "H37"
		)
		(pin "H38"
		)
		(pin "E02"
		)
		(pin "E03"
		)
		(pin "E06"
		)
		(pin "E07"
		)
		(pin "E09"
		)
		(pin "E10"
		)
		(pin "E12"
		)
		(pin "E13"
		)
		(pin "E15"
		)
		(pin "E16"
		)
		(pin "E18"
		)
		(pin "E19"
		)
		(pin "F04"
		)
		(pin "F05"
		)
		(pin "F07"
		)
		(pin "F08"
		)
		(pin "F10"
		)
		(pin "F11"
		)
		(pin "F13"
		)
		(pin "F14"
		)
		(pin "F16"
		)
		(pin "F17"
		)
		(pin "F19"
		)
		(pin "F20"
		)
		(pin "J06"
		)
		(pin "J07"
		)
		(pin "J09"
		)
		(pin "J10"
		)
		(pin "J12"
		)
		(pin "J13"
		)
		(pin "J15"
		)
		(pin "J16"
		)
		(pin "J18"
		)
		(pin "J19"
		)
		(pin "J21"
		)
		(pin "J22"
		)
		(pin "K07"
		)
		(pin "K08"
		)
		(pin "K10"
		)
		(pin "K11"
		)
		(pin "K13"
		)
		(pin "K14"
		)
		(pin "K16"
		)
		(pin "K17"
		)
		(pin "K19"
		)
		(pin "K20"
		)
		(pin "K22"
		)
		(pin "K23"
		)
		(pin "B01"
		)
		(pin "G02"
		)
		(pin "G03"
		)
		(pin "H04"
		)
		(pin "H05"
		)
		(pin "J02"
		)
		(pin "J03"
		)
		(pin "K04"
		)
		(pin "K05"
		)
		(pin "B20"
		)
		(pin "B21"
		)
		(pin "D04"
		)
		(pin "D05"
		)
		(pin "L04"
		)
		(pin "L05"
		)
		(pin "L08"
		)
		(pin "L09"
		)
		(pin "L12"
		)
		(pin "L13"
		)
		(pin "L16"
		)
		(pin "L17"
		)
		(pin "L20"
		)
		(pin "L21"
		)
		(pin "L24"
		)
		(pin "L25"
		)
		(pin "L28"
		)
		(pin "L29"
		)
		(pin "Z20"
		)
		(pin "Z21"
		)
		(pin "A02"
		)
		(pin "A03"
		)
		(pin "A06"
		)
		(pin "A07"
		)
		(pin "A10"
		)
		(pin "A11"
		)
		(pin "A14"
		)
		(pin "A15"
		)
		(pin "A18"
		)
		(pin "A19"
		)
		(pin "A22"
		)
		(pin "A23"
		)
		(pin "A26"
		)
		(pin "A27"
		)
		(pin "A30"
		)
		(pin "A31"
		)
		(pin "A34"
		)
		(pin "A35"
		)
		(pin "A38"
		)
		(pin "A39"
		)
		(pin "B04"
		)
		(pin "B05"
		)
		(pin "B08"
		)
		(pin "B09"
		)
		(pin "B12"
		)
		(pin "B13"
		)
		(pin "B16"
		)
		(pin "B17"
		)
		(pin "B24"
		)
		(pin "B25"
		)
		(pin "B28"
		)
		(pin "B29"
		)
		(pin "B32"
		)
		(pin "B33"
		)
		(pin "B36"
		)
		(pin "B37"
		)
		(pin "C02"
		)
		(pin "C03"
		)
		(pin "C06"
		)
		(pin "C07"
		)
		(pin "M02"
		)
		(pin "M03"
		)
		(pin "M06"
		)
		(pin "M07"
		)
		(pin "M10"
		)
		(pin "M11"
		)
		(pin "M14"
		)
		(pin "M15"
		)
		(pin "M18"
		)
		(pin "M39"
		)
		(pin "Y02"
		)
		(pin "Y03"
		)
		(pin "Y06"
		)
		(pin "Y07"
		)
		(pin "Y10"
		)
		(pin "Y11"
		)
		(pin "Y14"
		)
		(pin "Y15"
		)
		(pin "Y18"
		)
		(pin "Y19"
		)
		(pin "Y22"
		)
		(pin "Y23"
		)
		(pin "Y26"
		)
		(pin "Y27"
		)
		(pin "Y30"
		)
		(pin "Y31"
		)
		(pin "Y34"
		)
		(pin "Y35"
		)
		(pin "Y38"
		)
		(pin "Y39"
		)
		(pin "Z04"
		)
		(pin "Z05"
		)
		(pin "Z08"
		)
		(pin "Z09"
		)
		(pin "Z12"
		)
		(pin "Z13"
		)
		(pin "Z16"
		)
		(pin "Z17"
		)
		(pin "Z24"
		)
		(pin "Z25"
		)
		(pin "Z28"
		)
		(pin "Z29"
		)
		(pin "Z32"
		)
		(pin "Z33"
		)
		(pin "Z36"
		)
		(pin "Z37"
		)
		(instances
			(project "k410t-devboard"
				(path ""
					(reference "J18")
					(unit 5)
				)
			)
		)
	)
	(symbol
		(lib_id "antmicroCapacitors0402:C_100n_0402")
		(at 353.06 209.55 180)
		(unit 1)
		(exclude_from_sim no)
		(in_bom yes)
		(on_board yes)
		(dnp no)
		(property "Reference" "C310"
			(at 355.6 208.28 0)
			(effects
				(font
					(size 1.27 1.27)
				)
			)
		)
		(property "Value" "C_100n_0402"
			(at 332.74 199.39 0)
			(effects
				(font
					(size 1.27 1.27)
					(thickness 0.15)
				)
				(justify left bottom)
				(hide yes)
			)
		)
		(property "Footprint" "antmicro-footprints:C_0402_1005Metric"
			(at 332.74 196.85 0)
			(effects
				(font
					(size 1.27 1.27)
					(thickness 0.15)
				)
				(justify left bottom)
				(hide yes)
			)
		)
		(property "Datasheet" "https://www.murata.com/products/productdetail?partno=GRM155R61H104KE14%23"
			(at 332.74 194.31 0)
			(effects
				(font
					(size 1.27 1.27)
					(thickness 0.15)
				)
				(justify left bottom)
				(hide yes)
			)
		)
		(property "Description" ""
			(at 353.06 209.55 0)
			(effects
				(font
					(size 1.27 1.27)
				)
			)
		)
		(property "Manufacturer" "Murata"
			(at 332.74 189.23 0)
			(effects
				(font
					(size 1.27 1.27)
					(thickness 0.15)
				)
				(justify left bottom)
				(hide yes)
			)
		)
		(property "MPN" "GRM155R61H104KE14D"
			(at 332.74 191.77 0)
			(effects
				(font
					(size 1.27 1.27)
					(thickness 0.15)
				)
				(justify left bottom)
				(hide yes)
			)
		)
		(property "Val" "100n"
			(at 346.075 208.28 0)
			(effects
				(font
					(size 1.27 1.27)
					(thickness 0.15)
				)
			)
		)
		(property "License" "Apache-2.0"
			(at 332.74 186.69 0)
			(effects
				(font
					(size 1.27 1.27)
					(thickness 0.15)
				)
				(justify left bottom)
				(hide yes)
			)
		)
		(property "Author" "Antmicro"
			(at 332.74 184.15 0)
			(effects
				(font
					(size 1.27 1.27)
					(thickness 0.15)
				)
				(justify left bottom)
				(hide yes)
			)
		)
		(property "Voltage" "50V"
			(at 332.74 181.61 0)
			(effects
				(font
					(size 1.27 1.27)
				)
				(justify left bottom)
				(hide yes)
			)
		)
		(property "Dielectric" "X5R"
			(at 332.74 179.07 0)
			(effects
				(font
					(size 1.27 1.27)
				)
				(justify left bottom)
				(hide yes)
			)
		)
		(pin "1"
		)
		(pin "2"
		)
		(instances
			(project "k410t-devboard"
				(path ""
					(reference "C310")
					(unit 1)
				)
			)
		)
	)
	(symbol
		(lib_id "antmicroCapacitors0402:C_100n_0402")
		(at 353.06 219.71 180)
		(unit 1)
		(exclude_from_sim no)
		(in_bom yes)
		(on_board yes)
		(dnp no)
		(property "Reference" "C312"
			(at 355.6 218.44 0)
			(effects
				(font
					(size 1.27 1.27)
				)
			)
		)
		(property "Value" "C_100n_0402"
			(at 332.74 209.55 0)
			(effects
				(font
					(size 1.27 1.27)
					(thickness 0.15)
				)
				(justify left bottom)
				(hide yes)
			)
		)
		(property "Footprint" "antmicro-footprints:C_0402_1005Metric"
			(at 332.74 207.01 0)
			(effects
				(font
					(size 1.27 1.27)
					(thickness 0.15)
				)
				(justify left bottom)
				(hide yes)
			)
		)
		(property "Datasheet" "https://www.murata.com/products/productdetail?partno=GRM155R61H104KE14%23"
			(at 332.74 204.47 0)
			(effects
				(font
					(size 1.27 1.27)
					(thickness 0.15)
				)
				(justify left bottom)
				(hide yes)
			)
		)
		(property "Description" ""
			(at 353.06 219.71 0)
			(effects
				(font
					(size 1.27 1.27)
				)
			)
		)
		(property "Manufacturer" "Murata"
			(at 332.74 199.39 0)
			(effects
				(font
					(size 1.27 1.27)
					(thickness 0.15)
				)
				(justify left bottom)
				(hide yes)
			)
		)
		(property "MPN" "GRM155R61H104KE14D"
			(at 332.74 201.93 0)
			(effects
				(font
					(size 1.27 1.27)
					(thickness 0.15)
				)
				(justify left bottom)
				(hide yes)
			)
		)
		(property "Val" "100n"
			(at 346.075 218.44 0)
			(effects
				(font
					(size 1.27 1.27)
					(thickness 0.15)
				)
			)
		)
		(property "License" "Apache-2.0"
			(at 332.74 196.85 0)
			(effects
				(font
					(size 1.27 1.27)
					(thickness 0.15)
				)
				(justify left bottom)
				(hide yes)
			)
		)
		(property "Author" "Antmicro"
			(at 332.74 194.31 0)
			(effects
				(font
					(size 1.27 1.27)
					(thickness 0.15)
				)
				(justify left bottom)
				(hide yes)
			)
		)
		(property "Voltage" "50V"
			(at 332.74 191.77 0)
			(effects
				(font
					(size 1.27 1.27)
				)
				(justify left bottom)
				(hide yes)
			)
		)
		(property "Dielectric" "X5R"
			(at 332.74 189.23 0)
			(effects
				(font
					(size 1.27 1.27)
				)
				(justify left bottom)
				(hide yes)
			)
		)
		(pin "1"
		)
		(pin "2"
		)
		(instances
			(project "k410t-devboard"
				(path ""
					(reference "C312")
					(unit 1)
				)
			)
		)
	)
	(symbol
		(lib_id "antmicropower:+3.3V")
		(at 57.15 35.56 0)
		(unit 1)
		(exclude_from_sim no)
		(in_bom yes)
		(on_board yes)
		(dnp no)
		(property "Reference" "#PWR0507"
			(at 57.15 39.37 0)
			(effects
				(font
					(size 1.27 1.27)
				)
				(hide yes)
			)
		)
		(property "Value" "+3V3"
			(at 57.15 32.004 0)
			(effects
				(font
					(size 1.27 1.27)
				)
			)
		)
		(property "Footprint" ""
			(at 57.15 35.56 0)
			(effects
				(font
					(size 1.27 1.27)
				)
				(hide yes)
			)
		)
		(property "Datasheet" ""
			(at 57.15 35.56 0)
			(effects
				(font
					(size 1.27 1.27)
				)
				(hide yes)
			)
		)
		(property "Description" ""
			(at 57.15 35.56 0)
			(effects
				(font
					(size 1.27 1.27)
				)
			)
		)
		(pin "1"
		)
		(instances
			(project "k410t-devboard"
				(path ""
					(reference "#PWR0507")
					(unit 1)
				)
			)
		)
	)
	(symbol
		(lib_id "antmicroCapacitors0402:C_100n_0402")
		(at 353.06 184.15 180)
		(unit 1)
		(exclude_from_sim no)
		(in_bom yes)
		(on_board yes)
		(dnp no)
		(property "Reference" "C305"
			(at 355.6 182.88 0)
			(effects
				(font
					(size 1.27 1.27)
				)
			)
		)
		(property "Value" "C_100n_0402"
			(at 332.74 173.99 0)
			(effects
				(font
					(size 1.27 1.27)
					(thickness 0.15)
				)
				(justify left bottom)
				(hide yes)
			)
		)
		(property "Footprint" "antmicro-footprints:C_0402_1005Metric"
			(at 332.74 171.45 0)
			(effects
				(font
					(size 1.27 1.27)
					(thickness 0.15)
				)
				(justify left bottom)
				(hide yes)
			)
		)
		(property "Datasheet" "https://www.murata.com/products/productdetail?partno=GRM155R61H104KE14%23"
			(at 332.74 168.91 0)
			(effects
				(font
					(size 1.27 1.27)
					(thickness 0.15)
				)
				(justify left bottom)
				(hide yes)
			)
		)
		(property "Description" ""
			(at 353.06 184.15 0)
			(effects
				(font
					(size 1.27 1.27)
				)
			)
		)
		(property "Manufacturer" "Murata"
			(at 332.74 163.83 0)
			(effects
				(font
					(size 1.27 1.27)
					(thickness 0.15)
				)
				(justify left bottom)
				(hide yes)
			)
		)
		(property "MPN" "GRM155R61H104KE14D"
			(at 332.74 166.37 0)
			(effects
				(font
					(size 1.27 1.27)
					(thickness 0.15)
				)
				(justify left bottom)
				(hide yes)
			)
		)
		(property "Val" "100n"
			(at 346.075 182.245 0)
			(effects
				(font
					(size 1.27 1.27)
					(thickness 0.15)
				)
			)
		)
		(property "License" "Apache-2.0"
			(at 332.74 161.29 0)
			(effects
				(font
					(size 1.27 1.27)
					(thickness 0.15)
				)
				(justify left bottom)
				(hide yes)
			)
		)
		(property "Author" "Antmicro"
			(at 332.74 158.75 0)
			(effects
				(font
					(size 1.27 1.27)
					(thickness 0.15)
				)
				(justify left bottom)
				(hide yes)
			)
		)
		(property "Voltage" "50V"
			(at 332.74 156.21 0)
			(effects
				(font
					(size 1.27 1.27)
				)
				(justify left bottom)
				(hide yes)
			)
		)
		(property "Dielectric" "X5R"
			(at 332.74 153.67 0)
			(effects
				(font
					(size 1.27 1.27)
				)
				(justify left bottom)
				(hide yes)
			)
		)
		(pin "1"
		)
		(pin "2"
		)
		(instances
			(project "k410t-devboard"
				(path ""
					(reference "C305")
					(unit 1)
				)
			)
		)
	)
	(symbol
		(lib_id "antmicroCapacitors0402:C_100n_0402")
		(at 353.06 152.4 180)
		(unit 1)
		(exclude_from_sim no)
		(in_bom yes)
		(on_board yes)
		(dnp no)
		(property "Reference" "C299"
			(at 354.965 151.13 0)
			(effects
				(font
					(size 1.27 1.27)
				)
			)
		)
		(property "Value" "C_100n_0402"
			(at 332.74 142.24 0)
			(effects
				(font
					(size 1.27 1.27)
					(thickness 0.15)
				)
				(justify left bottom)
				(hide yes)
			)
		)
		(property "Footprint" "antmicro-footprints:C_0402_1005Metric"
			(at 332.74 139.7 0)
			(effects
				(font
					(size 1.27 1.27)
					(thickness 0.15)
				)
				(justify left bottom)
				(hide yes)
			)
		)
		(property "Datasheet" "https://www.murata.com/products/productdetail?partno=GRM155R61H104KE14%23"
			(at 332.74 137.16 0)
			(effects
				(font
					(size 1.27 1.27)
					(thickness 0.15)
				)
				(justify left bottom)
				(hide yes)
			)
		)
		(property "Description" ""
			(at 353.06 152.4 0)
			(effects
				(font
					(size 1.27 1.27)
				)
			)
		)
		(property "Manufacturer" "Murata"
			(at 332.74 132.08 0)
			(effects
				(font
					(size 1.27 1.27)
					(thickness 0.15)
				)
				(justify left bottom)
				(hide yes)
			)
		)
		(property "MPN" "GRM155R61H104KE14D"
			(at 332.74 134.62 0)
			(effects
				(font
					(size 1.27 1.27)
					(thickness 0.15)
				)
				(justify left bottom)
				(hide yes)
			)
		)
		(property "Val" "100n"
			(at 346.075 151.13 0)
			(effects
				(font
					(size 1.27 1.27)
					(thickness 0.15)
				)
			)
		)
		(property "License" "Apache-2.0"
			(at 332.74 129.54 0)
			(effects
				(font
					(size 1.27 1.27)
					(thickness 0.15)
				)
				(justify left bottom)
				(hide yes)
			)
		)
		(property "Author" "Antmicro"
			(at 332.74 127 0)
			(effects
				(font
					(size 1.27 1.27)
					(thickness 0.15)
				)
				(justify left bottom)
				(hide yes)
			)
		)
		(property "Voltage" "50V"
			(at 332.74 124.46 0)
			(effects
				(font
					(size 1.27 1.27)
				)
				(justify left bottom)
				(hide yes)
			)
		)
		(property "Dielectric" "X5R"
			(at 332.74 121.92 0)
			(effects
				(font
					(size 1.27 1.27)
				)
				(justify left bottom)
				(hide yes)
			)
		)
		(pin "1"
		)
		(pin "2"
		)
		(instances
			(project "k410t-devboard"
				(path ""
					(reference "C299")
					(unit 1)
				)
			)
		)
	)
	(symbol
		(lib_id "antmicroCapacitors0402:C_100n_0402")
		(at 353.06 147.32 180)
		(unit 1)
		(exclude_from_sim no)
		(in_bom yes)
		(on_board yes)
		(dnp no)
		(property "Reference" "C298"
			(at 354.965 146.05 0)
			(effects
				(font
					(size 1.27 1.27)
				)
			)
		)
		(property "Value" "C_100n_0402"
			(at 332.74 137.16 0)
			(effects
				(font
					(size 1.27 1.27)
					(thickness 0.15)
				)
				(justify left bottom)
				(hide yes)
			)
		)
		(property "Footprint" "antmicro-footprints:C_0402_1005Metric"
			(at 332.74 134.62 0)
			(effects
				(font
					(size 1.27 1.27)
					(thickness 0.15)
				)
				(justify left bottom)
				(hide yes)
			)
		)
		(property "Datasheet" "https://www.murata.com/products/productdetail?partno=GRM155R61H104KE14%23"
			(at 332.74 132.08 0)
			(effects
				(font
					(size 1.27 1.27)
					(thickness 0.15)
				)
				(justify left bottom)
				(hide yes)
			)
		)
		(property "Description" ""
			(at 353.06 147.32 0)
			(effects
				(font
					(size 1.27 1.27)
				)
			)
		)
		(property "Manufacturer" "Murata"
			(at 332.74 127 0)
			(effects
				(font
					(size 1.27 1.27)
					(thickness 0.15)
				)
				(justify left bottom)
				(hide yes)
			)
		)
		(property "MPN" "GRM155R61H104KE14D"
			(at 332.74 129.54 0)
			(effects
				(font
					(size 1.27 1.27)
					(thickness 0.15)
				)
				(justify left bottom)
				(hide yes)
			)
		)
		(property "Val" "100n"
			(at 346.075 146.05 0)
			(effects
				(font
					(size 1.27 1.27)
					(thickness 0.15)
				)
			)
		)
		(property "License" "Apache-2.0"
			(at 332.74 124.46 0)
			(effects
				(font
					(size 1.27 1.27)
					(thickness 0.15)
				)
				(justify left bottom)
				(hide yes)
			)
		)
		(property "Author" "Antmicro"
			(at 332.74 121.92 0)
			(effects
				(font
					(size 1.27 1.27)
					(thickness 0.15)
				)
				(justify left bottom)
				(hide yes)
			)
		)
		(property "Voltage" "50V"
			(at 332.74 119.38 0)
			(effects
				(font
					(size 1.27 1.27)
				)
				(justify left bottom)
				(hide yes)
			)
		)
		(property "Dielectric" "X5R"
			(at 332.74 116.84 0)
			(effects
				(font
					(size 1.27 1.27)
				)
				(justify left bottom)
				(hide yes)
			)
		)
		(pin "1"
		)
		(pin "2"
		)
		(instances
			(project "k410t-devboard"
				(path ""
					(reference "C298")
					(unit 1)
				)
			)
		)
	)
)
